FILE_TYPE = MACRO_DRAWING;
SET COLOR_WIRE YELLOW;
SET COLOR_PROP ORANGE;
SET COLOR_DOT WHITE;
SET COLOR_ARC YELLOW;
SET COLOR_BODY GREEN;
SET COLOR_NOTE PURPLE;
SET PROP_DISPLAY VALUE;
SET PAGE_NUMBER P34;
SET PATH_NUMBER P168;
FORCEADD LCMXO3LF2100C5BG256C..1
(-4900 4100);
FORCEPROP 2 LAST VALUE LCMXO3LF-2100C-5BG256C
J 0
(-5450 5575);
DISPLAY 0.680851 (-5450 5575);
FORCEPROP 2 LAST PART_TYPE SMLF
J 0
(-5450 5625);
DISPLAY 0.680851 (-5450 5625);
FORCEPROP 1 LAST MATERIAL IC
J 0
(-5470 5357);
DISPLAY 0.723404 (-5470 5357);
PAINT GREEN (-5470 5357);
FORCEPROP 1 LAST PART_NUMBER AJ021000T03
J 0
(-5470 5436);
DISPLAY 0.723404 (-5470 5436);
PAINT GREEN (-5470 5436);
FORCEPROP 2 LAST CDS_LIB pure_quanta
J 0
(-4900 4100);
DISPLAY INVISIBLE (-4900 4100);
FORCEPROP 1 LAST PATH I1
J 0
(-4900 4100);
DISPLAY 0.723404 (-4900 4100);
PAINT GREEN (-4900 4100);
DISPLAY INVISIBLE (-4900 4100);
FORCEPROP 1 LAST CDS_LMAN_SYM_OUTLINE -575,1250,575,-1250
J 0
(-4900 4100);
DISPLAY 0.468085 (-4900 4100);
PAINT GREEN (-4900 4100);
DISPLAY INVISIBLE (-4900 4100);
FORCEPROP 1 LAST NEEDS_NO_SIZE TRUE
J 0
(-4900 4100);
DISPLAY 0.723404 (-4900 4100);
PAINT GREEN (-4900 4100);
DISPLAY INVISIBLE (-4900 4100);
FORCEPROP 1 LAST LOCATION U25
J 0
(-5470 5535);
DISPLAY 0.723404 (-5470 5535);
PAINT GREEN (-5470 5535);
FORCEPROP 0 LASTPIN (-5625 5200) $PN C4
J 2
(-5635 5210);
DISPLAY 0.680851 (-5635 5210);
PAINT MONO (-5635 5210);
FORCEPROP 0 LASTPIN (-5625 5150) $PN B5
J 2
(-5635 5160);
DISPLAY 0.680851 (-5635 5160);
PAINT MONO (-5635 5160);
FORCEPROP 0 LASTPIN (-5625 5050) $PN B3
J 2
(-5635 5060);
DISPLAY 0.680851 (-5635 5060);
PAINT MONO (-5635 5060);
FORCEPROP 0 LASTPIN (-5625 4950) $PN A4
J 2
(-5635 4960);
DISPLAY 0.680851 (-5635 4960);
PAINT MONO (-5635 4960);
FORCEPROP 0 LASTPIN (-5625 4900) $PN C5
J 2
(-5635 4910);
DISPLAY 0.680851 (-5635 4910);
PAINT MONO (-5635 4910);
FORCEPROP 0 LASTPIN (-5625 4800) $PN A5
J 2
(-5635 4810);
DISPLAY 0.680851 (-5635 4810);
PAINT MONO (-5635 4810);
FORCEPROP 0 LASTPIN (-5625 4750) $PN B6
J 2
(-5635 4760);
DISPLAY 0.680851 (-5635 4760);
PAINT MONO (-5635 4760);
FORCEPROP 0 LASTPIN (-5625 4650) $PN A3
J 2
(-5635 4660);
DISPLAY 0.680851 (-5635 4660);
PAINT MONO (-5635 4660);
FORCEPROP 0 LASTPIN (-5625 4600) $PN B4
J 2
(-5635 4610);
DISPLAY 0.680851 (-5635 4610);
PAINT MONO (-5635 4610);
FORCEPROP 0 LASTPIN (-5625 4500) $PN D6
J 2
(-5635 4510);
DISPLAY 0.680851 (-5635 4510);
PAINT MONO (-5635 4510);
FORCEPROP 0 LASTPIN (-5625 4450) $PN E7
J 2
(-5635 4460);
DISPLAY 0.680851 (-5635 4460);
PAINT MONO (-5635 4460);
FORCEPROP 0 LASTPIN (-5625 4300) $PN C6
J 2
(-5635 4310);
DISPLAY 0.680851 (-5635 4310);
PAINT MONO (-5635 4310);
FORCEPROP 0 LASTPIN (-5625 4250) $PN A6
J 2
(-5635 4260);
DISPLAY 0.680851 (-5635 4260);
PAINT MONO (-5635 4260);
FORCEPROP 0 LASTPIN (-5625 4150) $PN B7
J 2
(-5635 4160);
DISPLAY 0.680851 (-5635 4160);
PAINT MONO (-5635 4160);
FORCEPROP 0 LASTPIN (-5625 4100) $PN C7
J 2
(-5635 4110);
DISPLAY 0.680851 (-5635 4110);
PAINT MONO (-5635 4110);
FORCEPROP 0 LASTPIN (-5625 4000) $PN E6
J 2
(-5635 4010);
DISPLAY 0.680851 (-5635 4010);
PAINT MONO (-5635 4010);
FORCEPROP 0 LASTPIN (-5625 3950) $PN D7
J 2
(-5635 3960);
DISPLAY 0.680851 (-5635 3960);
PAINT MONO (-5635 3960);
FORCEPROP 0 LASTPIN (-5625 3850) $PN F7
J 2
(-5635 3860);
DISPLAY 0.680851 (-5635 3860);
PAINT MONO (-5635 3860);
FORCEPROP 0 LASTPIN (-5625 3800) $PN E8
J 2
(-5635 3810);
DISPLAY 0.680851 (-5635 3810);
PAINT MONO (-5635 3810);
FORCEPROP 0 LASTPIN (-5625 3700) $PN A7
J 2
(-5635 3710);
DISPLAY 0.680851 (-5635 3710);
PAINT MONO (-5635 3710);
FORCEPROP 0 LASTPIN (-5625 3650) $PN B8
J 2
(-5635 3660);
DISPLAY 0.680851 (-5635 3660);
PAINT MONO (-5635 3660);
FORCEPROP 0 LASTPIN (-5625 3550) $PN C8
J 2
(-5635 3560);
DISPLAY 0.680851 (-5635 3560);
PAINT MONO (-5635 3560);
FORCEPROP 0 LASTPIN (-5625 3500) $PN A8
J 2
(-5635 3510);
DISPLAY 0.680851 (-5635 3510);
PAINT MONO (-5635 3510);
FORCEPROP 0 LASTPIN (-5625 3400) $PN D8
J 2
(-5635 3410);
DISPLAY 0.680851 (-5635 3410);
PAINT MONO (-5635 3410);
FORCEPROP 0 LASTPIN (-5625 3350) $PN E9
J 2
(-5635 3360);
DISPLAY 0.680851 (-5635 3360);
PAINT MONO (-5635 3360);
FORCEPROP 0 LASTPIN (-4175 5250) $PN F8
J 0
(-4165 5260);
DISPLAY 0.680851 (-4165 5260);
PAINT MONO (-4165 5260);
FORCEPROP 0 LASTPIN (-4175 5200) $PN D9
J 0
(-4165 5210);
DISPLAY 0.680851 (-4165 5210);
PAINT MONO (-4165 5210);
FORCEPROP 0 LASTPIN (-4175 5100) $PN A9
J 0
(-4165 5110);
DISPLAY 0.680851 (-4165 5110);
PAINT MONO (-4165 5110);
FORCEPROP 0 LASTPIN (-4175 5050) $PN C9
J 0
(-4165 5060);
DISPLAY 0.680851 (-4165 5060);
PAINT MONO (-4165 5060);
FORCEPROP 0 LASTPIN (-4175 4950) $PN B9
J 0
(-4165 4960);
DISPLAY 0.680851 (-4165 4960);
PAINT MONO (-4165 4960);
FORCEPROP 0 LASTPIN (-4175 4900) $PN A10
J 0
(-4165 4910);
DISPLAY 0.680851 (-4165 4910);
PAINT MONO (-4165 4910);
FORCEPROP 0 LASTPIN (-4175 4800) $PN F9
J 0
(-4165 4810);
DISPLAY 0.680851 (-4165 4810);
PAINT MONO (-4165 4810);
FORCEPROP 0 LASTPIN (-4175 4750) $PN E11
J 0
(-4165 4760);
DISPLAY 0.680851 (-4165 4760);
PAINT MONO (-4165 4760);
FORCEPROP 0 LASTPIN (-4175 4650) $PN D10
J 0
(-4165 4660);
DISPLAY 0.680851 (-4165 4660);
PAINT MONO (-4165 4660);
FORCEPROP 0 LASTPIN (-4175 4600) $PN E10
J 0
(-4165 4610);
DISPLAY 0.680851 (-4165 4610);
PAINT MONO (-4165 4610);
FORCEPROP 0 LASTPIN (-4175 4500) $PN C10
J 0
(-4165 4510);
DISPLAY 0.680851 (-4165 4510);
PAINT MONO (-4165 4510);
FORCEPROP 0 LASTPIN (-4175 4450) $PN B10
J 0
(-4165 4460);
DISPLAY 0.680851 (-4165 4460);
PAINT MONO (-4165 4460);
FORCEPROP 0 LASTPIN (-4175 4350) $PN A11
J 0
(-4165 4360);
DISPLAY 0.680851 (-4165 4360);
PAINT MONO (-4165 4360);
FORCEPROP 0 LASTPIN (-4175 4300) $PN C11
J 0
(-4165 4310);
DISPLAY 0.680851 (-4165 4310);
PAINT MONO (-4165 4310);
FORCEPROP 0 LASTPIN (-4175 4200) $PN F10
J 0
(-4165 4210);
DISPLAY 0.680851 (-4165 4210);
PAINT MONO (-4165 4210);
FORCEPROP 0 LASTPIN (-4175 4150) $PN D11
J 0
(-4165 4160);
DISPLAY 0.680851 (-4165 4160);
PAINT MONO (-4165 4160);
FORCEPROP 0 LASTPIN (-4175 4050) $PN B11
J 0
(-4165 4060);
DISPLAY 0.680851 (-4165 4060);
PAINT MONO (-4165 4060);
FORCEPROP 0 LASTPIN (-4175 4000) $PN A12
J 0
(-4165 4010);
DISPLAY 0.680851 (-4165 4010);
PAINT MONO (-4165 4010);
FORCEPROP 0 LASTPIN (-4175 3900) $PN B13
J 0
(-4165 3910);
DISPLAY 0.680851 (-4165 3910);
PAINT MONO (-4165 3910);
FORCEPROP 0 LASTPIN (-4175 3850) $PN A14
J 0
(-4165 3860);
DISPLAY 0.680851 (-4165 3860);
PAINT MONO (-4165 3860);
FORCEPROP 0 LASTPIN (-4175 3750) $PN C12
J 0
(-4165 3760);
DISPLAY 0.680851 (-4165 3760);
PAINT MONO (-4165 3760);
FORCEPROP 0 LASTPIN (-4175 3700) $PN B12
J 0
(-4165 3710);
DISPLAY 0.680851 (-4165 3710);
PAINT MONO (-4165 3710);
FORCEPROP 0 LASTPIN (-4175 3600) $PN B14
J 0
(-4165 3610);
DISPLAY 0.680851 (-4165 3610);
PAINT MONO (-4165 3610);
FORCEPROP 0 LASTPIN (-4175 3550) $PN A15
J 0
(-4165 3560);
DISPLAY 0.680851 (-4165 3560);
PAINT MONO (-4165 3560);
FORCEPROP 0 LASTPIN (-4175 3450) $PN A13
J 0
(-4165 3460);
DISPLAY 0.680851 (-4165 3460);
PAINT MONO (-4165 3460);
FORCEPROP 0 LASTPIN (-4175 3400) $PN C13
J 0
(-4165 3410);
DISPLAY 0.680851 (-4165 3410);
PAINT MONO (-4165 3410);
FORCEPROP 0 LASTPIN (-5625 3050) $PN D5
J 2
(-5635 3060);
DISPLAY 0.680851 (-5635 3060);
PAINT MONO (-5635 3060);
FORCEPROP 0 LASTPIN (-5625 3000) $PN D12
J 2
(-5635 3010);
DISPLAY 0.680851 (-5635 3010);
PAINT MONO (-5635 3010);
FORCEPROP 0 LASTPIN (-4175 3100) $PN G8
J 0
(-4165 3110);
DISPLAY 0.680851 (-4165 3110);
PAINT MONO (-4165 3110);
FORCEPROP 0 LASTPIN (-4175 3050) $PN G9
J 0
(-4165 3060);
DISPLAY 0.680851 (-4165 3060);
PAINT MONO (-4165 3060);
FORCEPROP 0 LAST $SEC 1
J 0
(-5450 5675);
DISPLAY 0.680851 (-5450 5675);
PAINT MONO (-5450 5675);
DISPLAY INVISIBLE (-5450 5675);
FORCEPROP 0 LAST CDS_SEC 1
J 0
(-5450 5675);
DISPLAY 0.680851 (-5450 5675);
DISPLAY INVISIBLE (-5450 5675);
FORCEADD OFFPAGE..1
(-8275 3500);
FORCEPROP 2 LAST $XR0 13 
J 0
(-8526 3500);
DISPLAY 0.638298 (-8526 3500);
PAINT MONO (-8526 3500);
FORCEPROP 2 LAST PATH I10
J 0
(-8475 3550);
DISPLAY 0.680851 (-8475 3550);
DISPLAY INVISIBLE (-8475 3550);
FORCEPROP 2 LAST CDS_LIB standard
J 0
(-8275 3500);
DISPLAY INVISIBLE (-8275 3500);
FORCEPROP 1 LAST OFFPAGE TRUE
J 0
(-7950 3375);
DISPLAY 0.872340 (-7950 3375);
PAINT GREEN (-7950 3375);
DISPLAY INVISIBLE (-7950 3375);
FORCEPROP 1 LAST COMMENT_BODY TRUE
J 0
(-8150 3400);
DISPLAY 0.872340 (-8150 3400);
PAINT PEACH (-8150 3400);
DISPLAY INVISIBLE (-8150 3400);
FORCEADD OFFPAGE..6
R 2
(-1075 5050);
FORCEPROP 2 LAST $XR0 12 
J 0
(-861 5050);
DISPLAY 0.638298 (-861 5050);
PAINT MONO (-861 5050);
FORCEPROP 2 LAST $XR1 21 
J 0
(-771 5050);
DISPLAY 0.638298 (-771 5050);
PAINT MONO (-771 5050);
FORCEPROP 2 LAST $XR2 36 
J 0
(-681 5050);
DISPLAY 0.638298 (-681 5050);
PAINT MONO (-681 5050);
FORCEPROP 2 LAST $XR3 46 
J 0
(-591 5050);
DISPLAY 0.638298 (-591 5050);
PAINT MONO (-591 5050);
FORCEPROP 2 LAST CDS_LIB standard
J 2
(-1075 5050);
DISPLAY INVISIBLE (-1075 5050);
FORCEPROP 1 LAST OFFPAGE TRUE
J 2
(-1400 4925);
DISPLAY 0.872340 (-1400 4925);
DISPLAY INVISIBLE (-1400 4925);
FORCEPROP 1 LAST COMMENT_BODY TRUE
J 2
(-1175 4975);
DISPLAY 0.872340 (-1175 4975);
PAINT GREEN (-1175 4975);
DISPLAY INVISIBLE (-1175 4975);
FORCEPROP 2 LAST PATH I105
J 2
(-800 5100);
DISPLAY 0.680851 (-800 5100);
DISPLAY INVISIBLE (-800 5100);
FORCEADD OFFPAGE..1
R 2
(-1075 5100);
FORCEPROP 2 LAST $XR0 12 
J 0
(-889 5100);
DISPLAY 0.638298 (-889 5100);
PAINT MONO (-889 5100);
FORCEPROP 2 LAST $XR1 21 
J 0
(-799 5100);
DISPLAY 0.638298 (-799 5100);
PAINT MONO (-799 5100);
FORCEPROP 2 LAST $XR2 36 
J 0
(-709 5100);
DISPLAY 0.638298 (-709 5100);
PAINT MONO (-709 5100);
FORCEPROP 2 LAST $XR3 46 
J 0
(-619 5100);
DISPLAY 0.638298 (-619 5100);
PAINT MONO (-619 5100);
FORCEPROP 2 LAST CDS_LIB standard
J 2
(-1075 5100);
DISPLAY INVISIBLE (-1075 5100);
FORCEPROP 1 LAST OFFPAGE TRUE
J 2
(-1400 4975);
DISPLAY 0.872340 (-1400 4975);
DISPLAY INVISIBLE (-1400 4975);
FORCEPROP 1 LAST COMMENT_BODY TRUE
J 2
(-1200 5000);
DISPLAY 0.872340 (-1200 5000);
PAINT GREEN (-1200 5000);
DISPLAY INVISIBLE (-1200 5000);
FORCEPROP 2 LAST PATH I106
J 2
(-825 5150);
DISPLAY 0.680851 (-825 5150);
DISPLAY INVISIBLE (-825 5150);
FORCEADD OFFPAGE..1
R 2
(-2775 3400);
FORCEPROP 2 LAST $XR0 34 
J 0
(-2589 3400);
DISPLAY 0.638298 (-2589 3400);
PAINT MONO (-2589 3400);
FORCEPROP 1 LAST COMMENT_BODY TRUE
J 2
(-2900 3300);
DISPLAY 0.872340 (-2900 3300);
PAINT PEACH (-2900 3300);
DISPLAY INVISIBLE (-2900 3300);
FORCEPROP 1 LAST OFFPAGE TRUE
J 2
(-3100 3275);
DISPLAY 0.872340 (-3100 3275);
PAINT GREEN (-3100 3275);
DISPLAY INVISIBLE (-3100 3275);
FORCEPROP 2 LAST CDS_LIB standard
J 2
(-2775 3400);
DISPLAY INVISIBLE (-2775 3400);
FORCEPROP 2 LAST PATH I107
J 0
(-2575 3450);
DISPLAY 0.680851 (-2575 3450);
DISPLAY INVISIBLE (-2575 3450);
FORCEADD OFFPAGE..5
(-8275 3850);
FORCEPROP 2 LAST $XR0 15 
J 0
(-8529 3850);
DISPLAY 0.638298 (-8529 3850);
PAINT MONO (-8529 3850);
FORCEPROP 2 LAST PATH I11
J 0
(-8475 3900);
DISPLAY 0.680851 (-8475 3900);
DISPLAY INVISIBLE (-8475 3900);
FORCEPROP 2 LAST CDS_LIB standard
J 0
(-8275 3850);
DISPLAY INVISIBLE (-8275 3850);
FORCEPROP 1 LAST OFFPAGE TRUE
J 0
(-7950 3725);
DISPLAY 0.872340 (-7950 3725);
PAINT GREEN (-7950 3725);
DISPLAY INVISIBLE (-7950 3725);
FORCEPROP 1 LAST COMMENT_BODY TRUE
J 0
(-8175 3775);
DISPLAY 0.872340 (-8175 3775);
PAINT PEACH (-8175 3775);
DISPLAY INVISIBLE (-8175 3775);
FORCEADD OFFPAGE..1
R 2
(-2775 3450);
FORCEPROP 2 LAST $XR0 34 
J 0
(-2589 3450);
DISPLAY 0.638298 (-2589 3450);
PAINT MONO (-2589 3450);
FORCEPROP 2 LAST PATH I111
J 0
(-2575 3500);
DISPLAY 0.680851 (-2575 3500);
DISPLAY INVISIBLE (-2575 3500);
FORCEPROP 2 LAST CDS_LIB standard
J 2
(-2775 3450);
DISPLAY INVISIBLE (-2775 3450);
FORCEPROP 1 LAST OFFPAGE TRUE
J 2
(-3100 3325);
DISPLAY 0.872340 (-3100 3325);
PAINT GREEN (-3100 3325);
DISPLAY INVISIBLE (-3100 3325);
FORCEPROP 1 LAST COMMENT_BODY TRUE
J 2
(-2900 3350);
DISPLAY 0.872340 (-2900 3350);
PAINT PEACH (-2900 3350);
DISPLAY INVISIBLE (-2900 3350);
FORCEADD OFFPAGE..2
R 2
(-8325 650);
FORCEPROP 2 LAST $XR0 34 
J 0
(-8549 650);
DISPLAY 0.638298 (-8549 650);
PAINT MONO (-8549 650);
FORCEPROP 2 LAST PATH I112
J 0
(-8575 700);
DISPLAY 0.680851 (-8575 700);
DISPLAY INVISIBLE (-8575 700);
FORCEPROP 1 LAST COMMENT_BODY TRUE
J 2
(-8280 555);
DISPLAY 0.872340 (-8280 555);
PAINT PEACH (-8280 555);
DISPLAY INVISIBLE (-8280 555);
FORCEPROP 1 LAST OFFPAGE TRUE
J 2
(-8650 525);
DISPLAY 0.872340 (-8650 525);
PAINT GREEN (-8650 525);
DISPLAY INVISIBLE (-8650 525);
FORCEPROP 2 LAST CDS_LIB standard
J 0
(-8325 650);
DISPLAY INVISIBLE (-8325 650);
FORCEADD OFFPAGE..2
R 2
(-8325 700);
FORCEPROP 2 LAST $XR0 36 
J 0
(-8549 700);
DISPLAY 0.638298 (-8549 700);
PAINT MONO (-8549 700);
FORCEPROP 2 LAST PATH I113
J 0
(-8575 750);
DISPLAY 0.680851 (-8575 750);
DISPLAY INVISIBLE (-8575 750);
FORCEPROP 1 LAST COMMENT_BODY TRUE
J 2
(-8280 605);
DISPLAY 0.872340 (-8280 605);
PAINT PEACH (-8280 605);
DISPLAY INVISIBLE (-8280 605);
FORCEPROP 1 LAST OFFPAGE TRUE
J 2
(-8650 575);
DISPLAY 0.872340 (-8650 575);
PAINT GREEN (-8650 575);
DISPLAY INVISIBLE (-8650 575);
FORCEPROP 2 LAST CDS_LIB standard
J 0
(-8325 700);
DISPLAY INVISIBLE (-8325 700);
FORCEADD OFFPAGE..2
R 2
(-8325 750);
FORCEPROP 2 LAST $XR0 34 
J 0
(-8549 750);
DISPLAY 0.638298 (-8549 750);
PAINT MONO (-8549 750);
FORCEPROP 2 LAST PATH I114
J 0
(-8575 800);
DISPLAY 0.680851 (-8575 800);
DISPLAY INVISIBLE (-8575 800);
FORCEPROP 1 LAST COMMENT_BODY TRUE
J 2
(-8280 655);
DISPLAY 0.872340 (-8280 655);
PAINT PEACH (-8280 655);
DISPLAY INVISIBLE (-8280 655);
FORCEPROP 1 LAST OFFPAGE TRUE
J 2
(-8650 625);
DISPLAY 0.872340 (-8650 625);
PAINT GREEN (-8650 625);
DISPLAY INVISIBLE (-8650 625);
FORCEPROP 2 LAST CDS_LIB standard
J 0
(-8325 750);
DISPLAY INVISIBLE (-8325 750);
FORCEADD Q_RES..1
(-6950 700);
FORCEPROP 1 LAST MATERIAL CHIP
J 0
(-6675 700);
DISPLAY 0.510638 (-6675 700);
PAINT SKYBLUE (-6675 700);
FORCEPROP 1 LAST VALUE 10K
J 2
(-6700 700);
DISPLAY 0.510638 (-6700 700);
PAINT SKYBLUE (-6700 700);
FORCEPROP 1 LAST PATH I115
J 0
(-7000 850);
DISPLAY 0.978723 (-7000 850);
PAINT WHITE (-7000 850);
DISPLAY INVISIBLE (-7000 850);
FORCEPROP 1 LAST PART_NUMBER CS31002FB08
J 0
(-7000 800);
DISPLAY 0.510638 (-7000 800);
PAINT WHITE (-7000 800);
DISPLAY INVISIBLE (-7000 800);
FORCEPROP 1 LAST PACK_TYPE 0402LF
J 0
(-6700 550);
DISPLAY 0.510638 (-6700 550);
PAINT SKYBLUE (-6700 550);
DISPLAY INVISIBLE (-6700 550);
FORCEPROP 1 LAST TOLERANCE 1%
J 0
(-6950 600);
DISPLAY 0.510638 (-6950 600);
PAINT SKYBLUE (-6950 600);
DISPLAY INVISIBLE (-6950 600);
FORCEPROP 1 LAST WATTAGE 1/16W
J 2
(-6975 550);
DISPLAY 0.510638 (-6975 550);
PAINT SKYBLUE (-6975 550);
DISPLAY INVISIBLE (-6975 550);
FORCEPROP 2 LAST CDS_LIB pure_quanta
J 0
(-6950 700);
DISPLAY INVISIBLE (-6950 700);
FORCEPROP 1 LAST LOCATION R809
J 0
(-7250 700);
DISPLAY 0.702128 (-7250 700);
PAINT YELLOW (-7250 700);
FORCEPROP 1 LASTPIN (-7050 700) $PN 1
J 0
(-7038 712);
DISPLAY 0.808511 (-7038 712);
PAINT WHITE (-7038 712);
FORCEPROP 1 LASTPIN (-6850 700) $PN 2
J 0
(-6888 712);
DISPLAY 0.808511 (-6888 712);
PAINT WHITE (-6888 712);
FORCEPROP 0 LAST $SEC 1
J 0
(-6625 750);
DISPLAY 0.680851 (-6625 750);
PAINT MONO (-6625 750);
DISPLAY INVISIBLE (-6625 750);
FORCEPROP 0 LAST CDS_SEC 1
J 0
(-6625 750);
DISPLAY 0.680851 (-6625 750);
DISPLAY INVISIBLE (-6625 750);
FORCEADD Q_RES..1
(-6950 650);
FORCEPROP 1 LAST MATERIAL CHIP
J 0
(-6675 650);
DISPLAY 0.510638 (-6675 650);
PAINT SKYBLUE (-6675 650);
FORCEPROP 1 LAST VALUE 10K
J 2
(-6700 650);
DISPLAY 0.510638 (-6700 650);
PAINT SKYBLUE (-6700 650);
FORCEPROP 1 LAST PATH I116
J 0
(-7000 800);
DISPLAY 0.978723 (-7000 800);
PAINT WHITE (-7000 800);
DISPLAY INVISIBLE (-7000 800);
FORCEPROP 1 LAST PART_NUMBER CS31002FB08
J 0
(-7000 750);
DISPLAY 0.510638 (-7000 750);
PAINT WHITE (-7000 750);
DISPLAY INVISIBLE (-7000 750);
FORCEPROP 1 LAST PACK_TYPE 0402LF
J 0
(-6700 500);
DISPLAY 0.510638 (-6700 500);
PAINT SKYBLUE (-6700 500);
DISPLAY INVISIBLE (-6700 500);
FORCEPROP 1 LAST TOLERANCE 1%
J 0
(-6950 550);
DISPLAY 0.510638 (-6950 550);
PAINT SKYBLUE (-6950 550);
DISPLAY INVISIBLE (-6950 550);
FORCEPROP 1 LAST WATTAGE 1/16W
J 2
(-6975 500);
DISPLAY 0.510638 (-6975 500);
PAINT SKYBLUE (-6975 500);
DISPLAY INVISIBLE (-6975 500);
FORCEPROP 2 LAST CDS_LIB pure_quanta
J 0
(-6950 650);
DISPLAY INVISIBLE (-6950 650);
FORCEPROP 1 LAST LOCATION R810
J 0
(-7250 650);
DISPLAY 0.702128 (-7250 650);
PAINT YELLOW (-7250 650);
FORCEPROP 1 LASTPIN (-7050 650) $PN 1
J 0
(-7038 662);
DISPLAY 0.808511 (-7038 662);
PAINT WHITE (-7038 662);
FORCEPROP 1 LASTPIN (-6850 650) $PN 2
J 0
(-6888 662);
DISPLAY 0.808511 (-6888 662);
PAINT WHITE (-6888 662);
FORCEPROP 0 LAST $SEC 1
J 0
(-6625 700);
DISPLAY 0.680851 (-6625 700);
PAINT MONO (-6625 700);
DISPLAY INVISIBLE (-6625 700);
FORCEPROP 0 LAST CDS_SEC 1
J 0
(-6625 700);
DISPLAY 0.680851 (-6625 700);
DISPLAY INVISIBLE (-6625 700);
FORCEADD Q_RES..1
(-6950 750);
FORCEPROP 1 LAST VALUE 10K
J 2
(-6700 750);
DISPLAY 0.510638 (-6700 750);
PAINT SKYBLUE (-6700 750);
FORCEPROP 1 LAST MATERIAL CHIP
J 0
(-6675 750);
DISPLAY 0.510638 (-6675 750);
PAINT SKYBLUE (-6675 750);
FORCEPROP 1 LAST PATH I117
J 0
(-7000 900);
DISPLAY 0.978723 (-7000 900);
PAINT WHITE (-7000 900);
DISPLAY INVISIBLE (-7000 900);
FORCEPROP 1 LAST PART_NUMBER CS31002FB08
J 0
(-7000 850);
DISPLAY 0.510638 (-7000 850);
PAINT WHITE (-7000 850);
DISPLAY INVISIBLE (-7000 850);
FORCEPROP 1 LAST PACK_TYPE 0402LF
J 0
(-6700 600);
DISPLAY 0.510638 (-6700 600);
PAINT SKYBLUE (-6700 600);
DISPLAY INVISIBLE (-6700 600);
FORCEPROP 1 LAST TOLERANCE 1%
J 0
(-6950 650);
DISPLAY 0.510638 (-6950 650);
PAINT SKYBLUE (-6950 650);
DISPLAY INVISIBLE (-6950 650);
FORCEPROP 1 LAST WATTAGE 1/16W
J 2
(-6975 600);
DISPLAY 0.510638 (-6975 600);
PAINT SKYBLUE (-6975 600);
DISPLAY INVISIBLE (-6975 600);
FORCEPROP 2 LAST CDS_LIB pure_quanta
J 0
(-6950 750);
DISPLAY INVISIBLE (-6950 750);
FORCEPROP 1 LAST LOCATION R808
J 0
(-7250 750);
DISPLAY 0.702128 (-7250 750);
PAINT YELLOW (-7250 750);
FORCEPROP 1 LASTPIN (-7050 750) $PN 1
J 0
(-7038 762);
DISPLAY 0.808511 (-7038 762);
PAINT WHITE (-7038 762);
FORCEPROP 1 LASTPIN (-6850 750) $PN 2
J 0
(-6888 762);
DISPLAY 0.808511 (-6888 762);
PAINT WHITE (-6888 762);
FORCEPROP 0 LAST $SEC 1
J 0
(-6625 800);
DISPLAY 0.680851 (-6625 800);
PAINT MONO (-6625 800);
DISPLAY INVISIBLE (-6625 800);
FORCEPROP 0 LAST CDS_SEC 1
J 0
(-6625 800);
DISPLAY 0.680851 (-6625 800);
DISPLAY INVISIBLE (-6625 800);
FORCEADD UNIVERSAL_POWER..1
(-6400 925);
FORCEPROP 3 LASTPIN (-6400 875) SIG_NAME PVCCIO_AUX_PLD\g
J 0
(-6390 885);
DISPLAY 0.659574 (-6390 885);
PAINT MONO (-6390 885);
DISPLAY INVISIBLE (-6390 885);
FORCEPROP 1 LAST HDL_POWER PVCCIO_AUX_PLD
J 1
(-6400 975);
DISPLAY 0.702128 (-6400 975);
PAINT GREEN (-6400 975);
FORCEPROP 1 LAST PATH I118
J 0
(-6350 950);
DISPLAY 0.872340 (-6350 950);
PAINT AQUA (-6350 950);
DISPLAY INVISIBLE (-6350 950);
FORCEPROP 2 LAST CDS_LIB logical_power
J 0
(-6400 925);
PAINT MONO (-6400 925);
DISPLAY INVISIBLE (-6400 925);
FORCEADD Q_RES..2
(-4375 950);
FORCEPROP 1 LAST PACK_TYPE 0402LF
J 0
(-4325 825);
DISPLAY 0.510638 (-4325 825);
PAINT SKYBLUE (-4325 825);
FORCEPROP 1 LAST MATERIAL CHIP
J 0
(-4335 875);
DISPLAY 0.510638 (-4335 875);
PAINT SKYBLUE (-4335 875);
FORCEPROP 1 LAST WATTAGE 1/16W
J 0
(-4335 925);
DISPLAY 0.510638 (-4335 925);
PAINT SKYBLUE (-4335 925);
FORCEPROP 1 LAST TOLERANCE 1%
J 0
(-4330 975);
DISPLAY 0.510638 (-4330 975);
PAINT SKYBLUE (-4330 975);
FORCEPROP 1 LAST VALUE 4.7K
J 0
(-4330 1025);
DISPLAY 0.510638 (-4330 1025);
PAINT SKYBLUE (-4330 1025);
FORCEPROP 1 LAST PATH I119
J 0
(-4325 1125);
DISPLAY 0.978723 (-4325 1125);
PAINT WHITE (-4325 1125);
DISPLAY INVISIBLE (-4325 1125);
FORCEPROP 2 LAST CDS_LIB pure_quanta
J 0
(-4375 950);
DISPLAY INVISIBLE (-4375 950);
FORCEPROP 1 LAST PART_NUMBER CS24702FB06
J 0
(-4335 825);
DISPLAY 0.510638 (-4335 825);
PAINT WHITE (-4335 825);
DISPLAY INVISIBLE (-4335 825);
FORCEPROP 1 LAST LOCATION R806
J 0
(-4330 1075);
DISPLAY 0.702128 (-4330 1075);
PAINT YELLOW (-4330 1075);
FORCEPROP 1 LASTPIN (-4375 1050) $PN 1
J 0
(-4370 1012);
DISPLAY 0.808511 (-4370 1012);
PAINT WHITE (-4370 1012);
FORCEPROP 1 LASTPIN (-4375 850) $PN 2
J 0
(-4370 860);
DISPLAY 0.808511 (-4370 860);
PAINT WHITE (-4370 860);
FORCEPROP 2 LAST $SEC 1
J 0
(-4325 1175);
DISPLAY 0.680851 (-4325 1175);
PAINT MONO (-4325 1175);
DISPLAY INVISIBLE (-4325 1175);
FORCEPROP 0 LAST CDS_SEC 1
J 0
(-4325 1175);
DISPLAY 0.680851 (-4325 1175);
PAINT MONO (-4325 1175);
DISPLAY INVISIBLE (-4325 1175);
FORCEADD OFFPAGE..5
(-8275 3800);
FORCEPROP 2 LAST $XR0 15 
J 0
(-8529 3800);
DISPLAY 0.638298 (-8529 3800);
PAINT MONO (-8529 3800);
FORCEPROP 2 LAST PATH I12
J 0
(-8475 3850);
DISPLAY 0.680851 (-8475 3850);
DISPLAY INVISIBLE (-8475 3850);
FORCEPROP 2 LAST CDS_LIB standard
J 0
(-8275 3800);
DISPLAY INVISIBLE (-8275 3800);
FORCEPROP 1 LAST OFFPAGE TRUE
J 0
(-7950 3675);
DISPLAY 0.872340 (-7950 3675);
PAINT GREEN (-7950 3675);
DISPLAY INVISIBLE (-7950 3675);
FORCEPROP 1 LAST COMMENT_BODY TRUE
J 0
(-8175 3725);
DISPLAY 0.872340 (-8175 3725);
PAINT PEACH (-8175 3725);
DISPLAY INVISIBLE (-8175 3725);
FORCEADD UNIVERSAL_POWER..1
(-4375 1275);
FORCEPROP 3 LASTPIN (-4375 1225) SIG_NAME P3V3_AUX\g
J 0
(-4365 1235);
DISPLAY 0.659574 (-4365 1235);
PAINT MONO (-4365 1235);
DISPLAY INVISIBLE (-4365 1235);
FORCEPROP 1 LAST HDL_POWER P3V3_AUX
J 1
(-4375 1325);
DISPLAY 0.702128 (-4375 1325);
PAINT GREEN (-4375 1325);
FORCEPROP 1 LAST PATH I120
J 0
(-4325 1300);
DISPLAY 0.872340 (-4325 1300);
PAINT AQUA (-4325 1300);
DISPLAY INVISIBLE (-4325 1300);
FORCEPROP 2 LAST CDS_LIB logical_power
J 0
(-4375 1275);
DISPLAY INVISIBLE (-4375 1275);
FORCEADD UNIVERSAL_GND..1
(-3975 825);
FORCEPROP 3 LASTPIN (-3975 875) SIG_NAME GND\g
J 0
(-3965 885);
DISPLAY 0.659574 (-3965 885);
PAINT MONO (-3965 885);
DISPLAY INVISIBLE (-3965 885);
FORCEPROP 1 LAST PATH I121
J 0
(-3900 825);
DISPLAY 0.872340 (-3900 825);
PAINT AQUA (-3900 825);
DISPLAY INVISIBLE (-3900 825);
FORCEPROP 1 LAST HDL_POWER GND
J 1
(-3950 750);
DISPLAY 0.702128 (-3950 750);
PAINT GREEN (-3950 750);
DISPLAY INVISIBLE (-3950 750);
FORCEPROP 2 LAST CDS_LIB logical_power
J 0
(-3975 825);
DISPLAY INVISIBLE (-3975 825);
FORCEADD Q_CAP..1
(-3975 1125);
FORCEPROP 1 LAST TOLERANCE 10%
J 0
(-3925 1075);
DISPLAY 0.510638 (-3925 1075);
PAINT SKYBLUE (-3925 1075);
FORCEPROP 1 LAST VOLTAGE 25V
J 0
(-3925 1125);
DISPLAY 0.510638 (-3925 1125);
PAINT SKYBLUE (-3925 1125);
FORCEPROP 1 LAST VALUE 0.1UF
J 0
(-3925 1175);
DISPLAY 0.510638 (-3925 1175);
PAINT SKYBLUE (-3925 1175);
FORCEPROP 1 LAST MATERIAL X7R
J 0
(-3925 1025);
DISPLAY 0.510638 (-3925 1025);
PAINT SKYBLUE (-3925 1025);
FORCEPROP 1 LAST PACK_TYPE 0402
J 0
(-3925 975);
DISPLAY 0.510638 (-3925 975);
PAINT SKYBLUE (-3925 975);
FORCEPROP 1 LAST PATH I122
J 0
(-3925 1275);
DISPLAY 0.978723 (-3925 1275);
PAINT WHITE (-3925 1275);
DISPLAY INVISIBLE (-3925 1275);
FORCEPROP 2 LAST CDS_LIB pure_quanta
J 0
(-3975 1125);
DISPLAY INVISIBLE (-3975 1125);
FORCEPROP 1 LAST PART_NUMBER CH4104K1B00
J 0
(-3925 975);
DISPLAY 0.510638 (-3925 975);
PAINT WHITE (-3925 975);
DISPLAY INVISIBLE (-3925 975);
FORCEPROP 1 LAST LOCATION C318
J 0
(-3925 1225);
DISPLAY 0.702128 (-3925 1225);
PAINT YELLOW (-3925 1225);
FORCEPROP 1 LASTPIN (-3975 1225) $PN 1
J 0
(-3965 1205);
DISPLAY 0.808511 (-3965 1205);
PAINT WHITE (-3965 1205);
FORCEPROP 1 LASTPIN (-3975 1025) $PN 2
J 0
(-3965 1005);
DISPLAY 0.808511 (-3965 1005);
PAINT WHITE (-3965 1005);
FORCEPROP 2 LAST $SEC 1
J 0
(-3925 1325);
DISPLAY 0.680851 (-3925 1325);
PAINT MONO (-3925 1325);
DISPLAY INVISIBLE (-3925 1325);
FORCEPROP 0 LAST CDS_SEC 1
J 0
(-3925 1325);
DISPLAY 0.680851 (-3925 1325);
PAINT MONO (-3925 1325);
DISPLAY INVISIBLE (-3925 1325);
FORCEADD UNIVERSAL_POWER..1
(-3975 1475);
FORCEPROP 3 LASTPIN (-3975 1425) SIG_NAME P3V3_AUX\g
J 0
(-3965 1435);
DISPLAY 0.659574 (-3965 1435);
PAINT MONO (-3965 1435);
DISPLAY INVISIBLE (-3965 1435);
FORCEPROP 1 LAST HDL_POWER P3V3_AUX
J 1
(-3975 1525);
DISPLAY 0.702128 (-3975 1525);
PAINT GREEN (-3975 1525);
FORCEPROP 1 LAST PATH I123
J 0
(-3925 1500);
DISPLAY 0.872340 (-3925 1500);
PAINT AQUA (-3925 1500);
DISPLAY INVISIBLE (-3925 1500);
FORCEPROP 2 LAST CDS_LIB logical_power
J 0
(-3975 1475);
DISPLAY INVISIBLE (-3975 1475);
FORCEADD UNIVERSAL_GND..1
(-2725 500);
FORCEPROP 3 LASTPIN (-2725 550) SIG_NAME GND\g
J 0
(-2715 560);
DISPLAY 0.659574 (-2715 560);
PAINT MONO (-2715 560);
DISPLAY INVISIBLE (-2715 560);
FORCEPROP 1 LAST PATH I124
J 0
(-2650 500);
DISPLAY 0.872340 (-2650 500);
PAINT AQUA (-2650 500);
DISPLAY INVISIBLE (-2650 500);
FORCEPROP 1 LAST HDL_POWER GND
J 1
(-2700 425);
DISPLAY 0.702128 (-2700 425);
PAINT GREEN (-2700 425);
DISPLAY INVISIBLE (-2700 425);
FORCEPROP 2 LAST CDS_LIB logical_power
J 0
(-2725 500);
DISPLAY INVISIBLE (-2725 500);
FORCEADD OFFPAGE..2
(-800 850);
FORCEPROP 2 LAST $XR0 34 
J 0
(-611 850);
DISPLAY 0.638298 (-611 850);
PAINT MONO (-611 850);
FORCEPROP 2 LAST PATH I125
J 0
(-600 900);
DISPLAY 0.680851 (-600 900);
DISPLAY INVISIBLE (-600 900);
FORCEPROP 1 LAST COMMENT_BODY TRUE
J 0
(-845 755);
DISPLAY 0.872340 (-845 755);
PAINT PEACH (-845 755);
DISPLAY INVISIBLE (-845 755);
FORCEPROP 1 LAST OFFPAGE TRUE
J 0
(-475 725);
DISPLAY 0.872340 (-475 725);
PAINT GREEN (-475 725);
DISPLAY INVISIBLE (-475 725);
FORCEPROP 2 LAST CDS_LIB standard
J 0
(-800 850);
DISPLAY INVISIBLE (-800 850);
FORCEADD Q_RES..1
(-1800 850);
FORCEPROP 1 LAST PACK_TYPE 0402LF
J 0
(-1700 775);
DISPLAY 0.510638 (-1700 775);
PAINT SKYBLUE (-1700 775);
FORCEPROP 1 LAST WATTAGE 1/16W
J 2
(-1875 775);
DISPLAY 0.510638 (-1875 775);
PAINT SKYBLUE (-1875 775);
FORCEPROP 1 LAST PART_NUMBER CS03322FB03
J 0
(-1950 725);
DISPLAY 0.510638 (-1950 725);
PAINT WHITE (-1950 725);
FORCEPROP 1 LAST TOLERANCE 1%
J 0
(-1600 725);
DISPLAY 0.510638 (-1600 725);
PAINT SKYBLUE (-1600 725);
FORCEPROP 1 LAST MATERIAL CHIP
J 0
(-1850 775);
DISPLAY 0.510638 (-1850 775);
PAINT SKYBLUE (-1850 775);
FORCEPROP 1 LAST VALUE 33.2
J 2
(-1550 850);
DISPLAY 0.510638 (-1550 850);
PAINT SKYBLUE (-1550 850);
FORCEPROP 1 LAST PATH I126
J 0
(-1850 1000);
DISPLAY 0.978723 (-1850 1000);
PAINT WHITE (-1850 1000);
DISPLAY INVISIBLE (-1850 1000);
FORCEPROP 2 LAST CDS_LIB pure_quanta
J 0
(-1800 850);
DISPLAY INVISIBLE (-1800 850);
FORCEPROP 1 LAST LOCATION R807
J 0
(-2025 850);
DISPLAY 0.702128 (-2025 850);
PAINT YELLOW (-2025 850);
FORCEPROP 1 LASTPIN (-1900 850) $PN 1
J 0
(-1888 862);
DISPLAY 0.808511 (-1888 862);
PAINT WHITE (-1888 862);
FORCEPROP 1 LASTPIN (-1700 850) $PN 2
J 0
(-1738 862);
DISPLAY 0.808511 (-1738 862);
PAINT WHITE (-1738 862);
FORCEPROP 2 LAST $SEC 1
J 0
(-1850 1050);
DISPLAY 0.680851 (-1850 1050);
PAINT MONO (-1850 1050);
DISPLAY INVISIBLE (-1850 1050);
FORCEPROP 0 LAST CDS_SEC 1
J 0
(-1850 1050);
DISPLAY 0.680851 (-1850 1050);
PAINT MONO (-1850 1050);
DISPLAY INVISIBLE (-1850 1050);
FORCEADD OSC4_7X25000018..1
(-3225 775);
FORCEPROP 1 LAST MATERIAL MISC
J 0
(-3405 917);
DISPLAY 0.510638 (-3405 917);
PAINT SKYBLUE (-3405 917);
FORCEPROP 1 LAST PART_NUMBER BF625000023
J 0
(-3405 988);
DISPLAY 0.510638 (-3405 988);
PAINT WHITE (-3405 988);
FORCEPROP 2 LAST PART_TYPE SMLF
J 0
(-3400 1175);
DISPLAY 0.510638 (-3400 1175);
PAINT SKYBLUE (-3400 1175);
FORCEPROP 2 LAST VALUE 25MHZ
J 0
(-3400 1125);
DISPLAY 0.510638 (-3400 1125);
PAINT SKYBLUE (-3400 1125);
FORCEPROP 1 LAST PATH I127
J 0
(-3225 775);
DISPLAY 0.723404 (-3225 775);
PAINT GREEN (-3225 775);
DISPLAY INVISIBLE (-3225 775);
FORCEPROP 1 LAST CDS_LMAN_SYM_OUTLINE -175,125,175,-125
J 0
(-3225 775);
DISPLAY 0.468085 (-3225 775);
PAINT GREEN (-3225 775);
DISPLAY INVISIBLE (-3225 775);
FORCEPROP 1 LAST PIN_NAMES_ROTATE True
J 0
(-3225 775);
DISPLAY 0.489362 (-3225 775);
PAINT GREEN (-3225 775);
DISPLAY INVISIBLE (-3225 775);
FORCEPROP 2 LAST CDS_LIB pure_quanta
J 0
(-3225 775);
DISPLAY INVISIBLE (-3225 775);
FORCEPROP 1 LAST LOCATION OSC2
J 0
(-3405 1066);
DISPLAY 0.702128 (-3405 1066);
PAINT YELLOW (-3405 1066);
FORCEPROP 2 LASTPIN (-2900 700) $PN 2
J 0
(-2890 710);
DISPLAY 0.808511 (-2890 710);
PAINT WHITE (-2890 710);
FORCEPROP 2 LASTPIN (-3550 700) $PN 1
J 2
(-3560 710);
DISPLAY 0.808511 (-3560 710);
PAINT WHITE (-3560 710);
FORCEPROP 2 LASTPIN (-2900 850) $PN 3
J 0
(-2890 860);
DISPLAY 0.808511 (-2890 860);
PAINT WHITE (-2890 860);
FORCEPROP 2 LASTPIN (-3550 850) $PN 4
J 2
(-3560 860);
DISPLAY 0.808511 (-3560 860);
PAINT WHITE (-3560 860);
FORCEPROP 2 LAST $SEC 1
J 0
(-3400 1200);
DISPLAY 0.680851 (-3400 1200);
PAINT MONO (-3400 1200);
DISPLAY INVISIBLE (-3400 1200);
FORCEPROP 0 LAST CDS_SEC 1
J 0
(-3400 1200);
DISPLAY 0.680851 (-3400 1200);
PAINT MONO (-3400 1200);
DISPLAY INVISIBLE (-3400 1200);
FORCEADD UNIVERSAL_POWER..1
(-3800 3200);
FORCEPROP 3 LASTPIN (-3800 3150) SIG_NAME VCCIO0\g
J 0
(-3790 3160);
DISPLAY 0.659574 (-3790 3160);
PAINT MONO (-3790 3160);
DISPLAY INVISIBLE (-3790 3160);
FORCEPROP 1 LAST HDL_POWER VCCIO0
J 1
(-3800 3250);
DISPLAY 0.702128 (-3800 3250);
PAINT GREEN (-3800 3250);
FORCEPROP 2 LAST CDS_LIB logical_power
J 0
(-3800 3200);
DISPLAY INVISIBLE (-3800 3200);
FORCEPROP 1 LAST PATH I128
J 0
(-3750 3225);
DISPLAY 0.872340 (-3750 3225);
PAINT AQUA (-3750 3225);
DISPLAY INVISIBLE (-3750 3225);
FORCEADD UNIVERSAL_POWER..1
(-6000 3150);
FORCEPROP 3 LASTPIN (-6000 3100) SIG_NAME VCCIO0\g
J 0
(-5990 3110);
DISPLAY 0.659574 (-5990 3110);
PAINT MONO (-5990 3110);
DISPLAY INVISIBLE (-5990 3110);
FORCEPROP 1 LAST HDL_POWER VCCIO0
J 1
(-6000 3200);
DISPLAY 0.702128 (-6000 3200);
PAINT GREEN (-6000 3200);
FORCEPROP 2 LAST CDS_LIB logical_power
J 0
(-6000 3150);
DISPLAY INVISIBLE (-6000 3150);
FORCEPROP 1 LAST PATH I129
J 0
(-5950 3175);
DISPLAY 0.872340 (-5950 3175);
PAINT AQUA (-5950 3175);
DISPLAY INVISIBLE (-5950 3175);
FORCEADD OFFPAGE..1
(-8275 3550);
FORCEPROP 2 LAST $XR0 34 
J 0
(-8526 3550);
DISPLAY 0.638298 (-8526 3550);
PAINT MONO (-8526 3550);
FORCEPROP 2 LAST PATH I13
J 0
(-8475 3600);
DISPLAY 0.680851 (-8475 3600);
DISPLAY INVISIBLE (-8475 3600);
FORCEPROP 2 LAST CDS_LIB standard
J 0
(-8275 3550);
DISPLAY INVISIBLE (-8275 3550);
FORCEPROP 1 LAST OFFPAGE TRUE
J 0
(-7950 3425);
DISPLAY 0.872340 (-7950 3425);
PAINT GREEN (-7950 3425);
DISPLAY INVISIBLE (-7950 3425);
FORCEPROP 1 LAST COMMENT_BODY TRUE
J 0
(-8150 3450);
DISPLAY 0.872340 (-8150 3450);
PAINT PEACH (-8150 3450);
DISPLAY INVISIBLE (-8150 3450);
FORCEADD OFFPAGE..4
(-1075 4500);
FORCEPROP 2 LAST $XR1 48 
J 0
(-799 4500);
DISPLAY 0.638298 (-799 4500);
PAINT MONO (-799 4500);
FORCEPROP 2 LAST $XR0 32 
J 0
(-889 4500);
DISPLAY 0.638298 (-889 4500);
PAINT MONO (-889 4500);
FORCEPROP 2 LAST PATH I130
J 0
(-775 4550);
DISPLAY 0.680851 (-775 4550);
DISPLAY INVISIBLE (-775 4550);
FORCEPROP 2 LAST CDS_LIB standard
J 0
(-1075 4500);
DISPLAY INVISIBLE (-1075 4500);
FORCEPROP 1 LAST OFFPAGE TRUE
J 0
(-750 4375);
DISPLAY 0.872340 (-750 4375);
PAINT GREEN (-750 4375);
DISPLAY INVISIBLE (-750 4375);
FORCEPROP 1 LAST COMMENT_BODY TRUE
J 0
(-1100 4400);
DISPLAY 0.872340 (-1100 4400);
PAINT PEACH (-1100 4400);
DISPLAY INVISIBLE (-1100 4400);
FORCEADD UNIVERSAL_POWER..1
(-600 4525);
FORCEPROP 3 LASTPIN (-600 4475) SIG_NAME VCCIO2\g
J 0
(-590 4485);
DISPLAY 0.659574 (-590 4485);
PAINT MONO (-590 4485);
DISPLAY INVISIBLE (-590 4485);
FORCEPROP 1 LAST HDL_POWER VCCIO2
J 1
(-600 4550);
DISPLAY 0.553191 (-600 4550);
PAINT GREEN (-600 4550);
FORCEPROP 1 LAST PATH I136
J 0
(-591 4591);
DISPLAY 0.872340 (-591 4591);
PAINT AQUA (-591 4591);
DISPLAY INVISIBLE (-591 4591);
FORCEPROP 2 LAST CDS_LIB logical_power
J 0
(-647 4572);
DISPLAY INVISIBLE (-647 4572);
FORCEADD Q_RES..1
(-2550 4450);
FORCEPROP 1 LAST PART_NUMBER CS31002FB08
J 0
(-2850 4425);
DISPLAY 0.510638 (-2850 4425);
PAINT WHITE (-2850 4425);
FORCEPROP 1 LAST MATERIAL CHIP
J 0
(-2325 4450);
DISPLAY 0.510638 (-2325 4450);
PAINT SKYBLUE (-2325 4450);
FORCEPROP 1 LAST VALUE 10K
J 2
(-2350 4450);
DISPLAY 0.510638 (-2350 4450);
PAINT SKYBLUE (-2350 4450);
FORCEPROP 1 LAST WATTAGE 1/16W
J 2
(-2850 4300);
DISPLAY 0.510638 (-2850 4300);
PAINT SKYBLUE (-2850 4300);
DISPLAY INVISIBLE (-2850 4300);
FORCEPROP 1 LAST PACK_TYPE 0402LF
J 0
(-2475 4300);
DISPLAY 0.510638 (-2475 4300);
PAINT SKYBLUE (-2475 4300);
DISPLAY INVISIBLE (-2475 4300);
FORCEPROP 1 LAST TOLERANCE 1%
J 0
(-2600 4300);
DISPLAY 0.510638 (-2600 4300);
PAINT SKYBLUE (-2600 4300);
DISPLAY INVISIBLE (-2600 4300);
FORCEPROP 1 LAST PATH I137
J 0
(-2600 4600);
DISPLAY 0.978723 (-2600 4600);
PAINT WHITE (-2600 4600);
DISPLAY INVISIBLE (-2600 4600);
FORCEPROP 2 LAST CDS_LIB pure_quanta
J 0
(-2550 4450);
DISPLAY INVISIBLE (-2550 4450);
FORCEPROP 1 LAST LOCATION R297
J 0
(-2850 4450);
DISPLAY 0.702128 (-2850 4450);
PAINT YELLOW (-2850 4450);
FORCEPROP 1 LASTPIN (-2650 4450) $PN 1
J 0
(-2638 4462);
DISPLAY 0.787234 (-2638 4462);
PAINT MONO (-2638 4462);
FORCEPROP 1 LASTPIN (-2450 4450) $PN 2
J 0
(-2488 4462);
DISPLAY 0.787234 (-2488 4462);
PAINT MONO (-2488 4462);
FORCEPROP 0 LAST $SEC 1
J 0
(-2725 4500);
DISPLAY 0.680851 (-2725 4500);
PAINT MONO (-2725 4500);
DISPLAY INVISIBLE (-2725 4500);
FORCEPROP 0 LAST CDS_SEC 1
J 0
(-2725 4500);
DISPLAY 0.680851 (-2725 4500);
DISPLAY INVISIBLE (-2725 4500);
FORCEADD UNIVERSAL_POWER..1
(-8400 2150);
FORCEPROP 3 LASTPIN (-8400 2100) SIG_NAME P3V3_AUX\g
J 0
(-8390 2110);
DISPLAY 0.659574 (-8390 2110);
PAINT MONO (-8390 2110);
DISPLAY INVISIBLE (-8390 2110);
FORCEPROP 1 LAST HDL_POWER P3V3_AUX
J 1
(-8400 2200);
DISPLAY 0.702128 (-8400 2200);
PAINT GREEN (-8400 2200);
FORCEPROP 2 LAST CDS_LIB logical_power
J 0
(-8400 2150);
DISPLAY INVISIBLE (-8400 2150);
FORCEPROP 1 LAST PATH I138
J 0
(-8350 2175);
DISPLAY 0.872340 (-8350 2175);
PAINT AQUA (-8350 2175);
DISPLAY INVISIBLE (-8350 2175);
FORCEADD Q_RES..1
(-8200 1850);
FORCEPROP 1 LAST MATERIAL CHIP
J 0
(-8200 1700);
DISPLAY 0.510638 (-8200 1700);
PAINT SKYBLUE (-8200 1700);
FORCEPROP 1 LAST TOLERANCE 5%
J 0
(-8200 1750);
DISPLAY 0.510638 (-8200 1750);
PAINT SKYBLUE (-8200 1750);
FORCEPROP 1 LAST PACK_TYPE 0402LF
J 0
(-8075 1700);
DISPLAY 0.510638 (-8075 1700);
PAINT SKYBLUE (-8075 1700);
FORCEPROP 1 LAST VALUE 0
J 2
(-8225 1750);
DISPLAY 0.510638 (-8225 1750);
PAINT SKYBLUE (-8225 1750);
FORCEPROP 1 LAST WATTAGE 1/16W
J 2
(-8225 1700);
DISPLAY 0.510638 (-8225 1700);
PAINT SKYBLUE (-8225 1700);
FORCEPROP 1 LAST PART_NUMBER CS00002JB13
J 0
(-8050 1875);
DISPLAY 0.510638 (-8050 1875);
PAINT WHITE (-8050 1875);
FORCEPROP 2 LAST CDS_LIB pure_quanta
J 0
(-8200 1850);
DISPLAY INVISIBLE (-8200 1850);
FORCEPROP 1 LAST PATH I139
J 0
(-8250 2000);
DISPLAY 0.978723 (-8250 2000);
PAINT WHITE (-8250 2000);
DISPLAY INVISIBLE (-8250 2000);
FORCEPROP 1 LAST $LOCATION R183
J 0
(-8250 1900);
DISPLAY 0.978723 (-8250 1900);
FORCEPROP 1 LASTPIN (-8300 1850) $PN 1
J 0
(-8288 1862);
DISPLAY 0.787234 (-8288 1862);
PAINT MONO (-8288 1862);
FORCEPROP 1 LASTPIN (-8100 1850) $PN 2
J 0
(-8138 1862);
DISPLAY 0.787234 (-8138 1862);
PAINT MONO (-8138 1862);
FORCEPROP 0 LAST CDS_LOCATION R183
J 0
(-8250 1950);
DISPLAY 0.680851 (-8250 1950);
DISPLAY INVISIBLE (-8250 1950);
FORCEPROP 0 LAST $SEC 1
J 0
(-8250 1950);
DISPLAY 0.680851 (-8250 1950);
PAINT MONO (-8250 1950);
DISPLAY INVISIBLE (-8250 1950);
FORCEPROP 0 LAST CDS_SEC 1
J 0
(-8250 1950);
DISPLAY 0.680851 (-8250 1950);
DISPLAY INVISIBLE (-8250 1950);
FORCEADD Q_CAP..1
(-7375 1650);
FORCEPROP 1 LAST TOLERANCE 10%
J 0
(-7325 1600);
DISPLAY 0.978723 (-7325 1600);
FORCEPROP 1 LAST VALUE 1UF
J 0
(-7325 1700);
DISPLAY 0.978723 (-7325 1700);
FORCEPROP 1 LAST VOLTAGE 25V
J 0
(-7325 1650);
DISPLAY 0.978723 (-7325 1650);
FORCEPROP 1 LAST MATERIAL X6S
J 0
(-7325 1550);
DISPLAY 0.978723 (-7325 1550);
FORCEPROP 1 LAST PACK_TYPE C0402
J 0
(-7325 1450);
DISPLAY 0.978723 (-7325 1450);
FORCEPROP 1 LAST PART_NUMBER CH5104KEB02
J 0
(-7325 1500);
DISPLAY 0.978723 (-7325 1500);
FORCEPROP 1 LAST PATH I140
J 0
(-7325 1800);
DISPLAY 0.978723 (-7325 1800);
PAINT WHITE (-7325 1800);
DISPLAY INVISIBLE (-7325 1800);
FORCEPROP 2 LAST CDS_LIB pure_quanta
J 0
(-7375 1650);
DISPLAY INVISIBLE (-7375 1650);
FORCEPROP 1 LAST $LOCATION C256
J 0
(-7325 1750);
DISPLAY 0.978723 (-7325 1750);
FORCEPROP 1 LASTPIN (-7375 1750) $PN 1
J 0
(-7365 1730);
DISPLAY 0.787234 (-7365 1730);
PAINT MONO (-7365 1730);
FORCEPROP 1 LASTPIN (-7375 1550) $PN 2
J 0
(-7365 1530);
DISPLAY 0.787234 (-7365 1530);
PAINT MONO (-7365 1530);
FORCEPROP 0 LAST CDS_LOCATION C256
J 0
(-7325 1800);
DISPLAY 0.680851 (-7325 1800);
DISPLAY INVISIBLE (-7325 1800);
FORCEPROP 0 LAST $SEC 1
J 0
(-7325 1800);
DISPLAY 0.680851 (-7325 1800);
PAINT MONO (-7325 1800);
DISPLAY INVISIBLE (-7325 1800);
FORCEPROP 0 LAST CDS_SEC 1
J 0
(-7325 1800);
DISPLAY 0.680851 (-7325 1800);
DISPLAY INVISIBLE (-7325 1800);
FORCEADD UNIVERSAL_GND..1
(-6725 1200);
FORCEPROP 3 LASTPIN (-6725 1250) SIG_NAME GND\g
J 0
(-6715 1260);
DISPLAY 0.659574 (-6715 1260);
PAINT MONO (-6715 1260);
DISPLAY INVISIBLE (-6715 1260);
FORCEPROP 2 LAST ROOM IO_SLOT
J 1
(-6950 1275);
DISPLAY 0.744681 (-6950 1275);
DISPLAY INVISIBLE (-6950 1275);
FORCEPROP 1 LAST HDL_POWER GND
J 1
(-6700 1125);
DISPLAY 0.702128 (-6700 1125);
PAINT GREEN (-6700 1125);
DISPLAY INVISIBLE (-6700 1125);
FORCEPROP 2 LAST CDS_LIB logical_power
J 0
(-6725 1200);
DISPLAY INVISIBLE (-6725 1200);
FORCEPROP 1 LAST PATH I141
J 0
(-6650 1200);
DISPLAY 0.872340 (-6650 1200);
PAINT AQUA (-6650 1200);
DISPLAY INVISIBLE (-6650 1200);
FORCEADD UNIVERSAL_POWER..1
(-6350 1950);
FORCEPROP 3 LASTPIN (-6350 1900) SIG_NAME PVCCIO_AUX_PLD\g
J 0
(-6340 1910);
DISPLAY 0.659574 (-6340 1910);
PAINT MONO (-6340 1910);
DISPLAY INVISIBLE (-6340 1910);
FORCEPROP 1 LAST HDL_POWER PVCCIO_AUX_PLD
J 1
(-6350 2000);
DISPLAY 0.702128 (-6350 2000);
PAINT GREEN (-6350 2000);
FORCEPROP 2 LAST CDS_LIB logical_power
J 0
(-6350 1950);
DISPLAY INVISIBLE (-6350 1950);
FORCEPROP 1 LAST PATH I143
J 0
(-6300 1975);
DISPLAY 0.872340 (-6300 1975);
PAINT AQUA (-6300 1975);
DISPLAY INVISIBLE (-6300 1975);
FORCEADD Q_CAP..1
(-6725 1625);
FORCEPROP 1 LAST VOLTAGE 25V
J 0
(-6675 1625);
DISPLAY 0.978723 (-6675 1625);
FORCEPROP 1 LAST PACK_TYPE 0402
J 0
(-6675 1425);
DISPLAY 0.978723 (-6675 1425);
FORCEPROP 1 LAST TOLERANCE 10%
J 0
(-6675 1575);
DISPLAY 0.978723 (-6675 1575);
FORCEPROP 1 LAST MATERIAL X7R
J 0
(-6675 1525);
DISPLAY 0.978723 (-6675 1525);
FORCEPROP 1 LAST PART_NUMBER CH4104K1B00
J 0
(-6675 1475);
DISPLAY 0.978723 (-6675 1475);
FORCEPROP 1 LAST VALUE 0.1UF
J 0
(-6675 1675);
DISPLAY 0.978723 (-6675 1675);
FORCEPROP 2 LAST CDS_LIB pure_quanta
J 0
(-6725 1625);
DISPLAY INVISIBLE (-6725 1625);
FORCEPROP 1 LAST PATH I144
J 0
(-6675 1775);
DISPLAY 0.978723 (-6675 1775);
PAINT WHITE (-6675 1775);
DISPLAY INVISIBLE (-6675 1775);
FORCEPROP 1 LAST $LOCATION C257
J 0
(-6675 1725);
DISPLAY 0.978723 (-6675 1725);
FORCEPROP 1 LASTPIN (-6725 1725) $PN 1
J 0
(-6715 1705);
DISPLAY 0.787234 (-6715 1705);
PAINT MONO (-6715 1705);
FORCEPROP 1 LASTPIN (-6725 1525) $PN 2
J 0
(-6715 1505);
DISPLAY 0.787234 (-6715 1505);
PAINT MONO (-6715 1505);
FORCEPROP 0 LAST CDS_LOCATION C257
J 0
(-6675 1775);
DISPLAY 0.680851 (-6675 1775);
DISPLAY INVISIBLE (-6675 1775);
FORCEPROP 0 LAST $SEC 1
J 0
(-6675 1775);
DISPLAY 0.680851 (-6675 1775);
PAINT MONO (-6675 1775);
DISPLAY INVISIBLE (-6675 1775);
FORCEPROP 0 LAST CDS_SEC 1
J 0
(-6675 1775);
DISPLAY 0.680851 (-6675 1775);
DISPLAY INVISIBLE (-6675 1775);
FORCEADD OFFPAGE..1
(-8275 4600);
FORCEPROP 2 LAST $XR0 11 
J 0
(-8526 4600);
DISPLAY 0.638298 (-8526 4600);
PAINT MONO (-8526 4600);
FORCEPROP 2 LAST $XR1 13 
J 0
(-8616 4600);
DISPLAY 0.638298 (-8616 4600);
PAINT MONO (-8616 4600);
FORCEPROP 2 LAST CDS_LIB standard
J 0
(-8275 4600);
DISPLAY INVISIBLE (-8275 4600);
FORCEPROP 1 LAST OFFPAGE TRUE
J 0
(-7950 4475);
DISPLAY 0.872340 (-7950 4475);
DISPLAY INVISIBLE (-7950 4475);
FORCEPROP 1 LAST COMMENT_BODY TRUE
J 0
(-8150 4500);
DISPLAY 0.872340 (-8150 4500);
PAINT GREEN (-8150 4500);
DISPLAY INVISIBLE (-8150 4500);
FORCEPROP 2 LAST PATH I145
J 0
(-8525 4650);
DISPLAY 0.680851 (-8525 4650);
DISPLAY INVISIBLE (-8525 4650);
FORCEADD Q_RES..1
(-7125 4000);
FORCEPROP 1 LAST MATERIAL CHIP
J 0
(-6925 4000);
DISPLAY 0.510638 (-6925 4000);
PAINT SKYBLUE (-6925 4000);
FORCEPROP 1 LAST VALUE 0
J 2
(-6975 4000);
DISPLAY 0.510638 (-6975 4000);
PAINT SKYBLUE (-6975 4000);
FORCEPROP 1 LAST PACK_TYPE 0402LF
J 0
(-7150 4050);
DISPLAY 0.510638 (-7150 4050);
PAINT SKYBLUE (-7150 4050);
DISPLAY INVISIBLE (-7150 4050);
FORCEPROP 1 LAST WATTAGE 1/16W
J 2
(-6775 4100);
DISPLAY 0.510638 (-6775 4100);
PAINT SKYBLUE (-6775 4100);
DISPLAY INVISIBLE (-6775 4100);
FORCEPROP 1 LAST TOLERANCE 5%
J 0
(-7200 4100);
DISPLAY 0.510638 (-7200 4100);
PAINT SKYBLUE (-7200 4100);
DISPLAY INVISIBLE (-7200 4100);
FORCEPROP 1 LAST PART_NUMBER CS00002JB13
J 0
(-7225 4075);
DISPLAY 0.510638 (-7225 4075);
PAINT WHITE (-7225 4075);
DISPLAY INVISIBLE (-7225 4075);
FORCEPROP 1 LAST PATH I147
J 0
(-7175 4150);
DISPLAY 0.978723 (-7175 4150);
PAINT WHITE (-7175 4150);
DISPLAY INVISIBLE (-7175 4150);
FORCEPROP 2 LAST CDS_LIB pure_quanta
J 0
(-7125 4000);
DISPLAY INVISIBLE (-7125 4000);
FORCEPROP 1 LAST LOCATION R519
J 0
(-7325 4000);
DISPLAY 0.702128 (-7325 4000);
PAINT YELLOW (-7325 4000);
FORCEPROP 1 LASTPIN (-7225 4000) $PN 1
J 0
(-7213 4012);
DISPLAY 0.787234 (-7213 4012);
PAINT MONO (-7213 4012);
FORCEPROP 1 LASTPIN (-7025 4000) $PN 2
J 0
(-7063 4012);
DISPLAY 0.787234 (-7063 4012);
PAINT MONO (-7063 4012);
FORCEPROP 0 LAST $SEC 1
J 0
(-7325 4050);
DISPLAY 0.680851 (-7325 4050);
PAINT MONO (-7325 4050);
DISPLAY INVISIBLE (-7325 4050);
FORCEPROP 0 LAST CDS_SEC 1
J 0
(-7325 4050);
DISPLAY 0.680851 (-7325 4050);
DISPLAY INVISIBLE (-7325 4050);
FORCEADD OFFPAGE..6
(-8275 4000);
FORCEPROP 2 LAST $XR1 42 
J 0
(-8644 4000);
DISPLAY 0.638298 (-8644 4000);
PAINT MONO (-8644 4000);
FORCEPROP 2 LAST $XR0 13 
J 0
(-8554 4000);
DISPLAY 0.638298 (-8554 4000);
PAINT MONO (-8554 4000);
FORCEPROP 2 LAST $XR2 31 
J 0
(-8734 4000);
DISPLAY 0.638298 (-8734 4000);
PAINT MONO (-8734 4000);
FORCEPROP 1 LAST COMMENT_BODY TRUE
J 0
(-8175 3925);
DISPLAY 0.872340 (-8175 3925);
PAINT GREEN (-8175 3925);
DISPLAY INVISIBLE (-8175 3925);
FORCEPROP 1 LAST OFFPAGE TRUE
J 0
(-7950 3875);
DISPLAY 0.872340 (-7950 3875);
DISPLAY INVISIBLE (-7950 3875);
FORCEPROP 2 LAST PATH I148
J 0
(-8225 4075);
DISPLAY 0.680851 (-8225 4075);
DISPLAY INVISIBLE (-8225 4075);
FORCEPROP 2 LAST CDS_LIB standard
J 0
(-8275 4000);
DISPLAY INVISIBLE (-8275 4000);
FORCEADD OFFPAGE..5
(-8275 3950);
FORCEPROP 2 LAST $XR0 27 
J 0
(-8529 3950);
DISPLAY 0.638298 (-8529 3950);
PAINT MONO (-8529 3950);
FORCEPROP 2 LAST $XR1 13 
J 0
(-8619 3950);
DISPLAY 0.638298 (-8619 3950);
PAINT MONO (-8619 3950);
FORCEPROP 2 LAST PATH I15
J 0
(-8525 4000);
DISPLAY 0.680851 (-8525 4000);
DISPLAY INVISIBLE (-8525 4000);
FORCEPROP 2 LAST CDS_LIB standard
J 0
(-8275 3950);
DISPLAY INVISIBLE (-8275 3950);
FORCEPROP 1 LAST OFFPAGE TRUE
J 0
(-7950 3825);
DISPLAY 0.872340 (-7950 3825);
DISPLAY INVISIBLE (-7950 3825);
FORCEPROP 1 LAST COMMENT_BODY TRUE
J 0
(-8175 3875);
DISPLAY 0.872340 (-8175 3875);
PAINT GREEN (-8175 3875);
DISPLAY INVISIBLE (-8175 3875);
FORCEADD Q_RES..1
(-7000 5200);
FORCEPROP 1 LAST VALUE 33.2
J 2
(-6775 5200);
DISPLAY 0.510638 (-6775 5200);
PAINT SKYBLUE (-6775 5200);
FORCEPROP 1 LAST MATERIAL CHIP
J 0
(-6750 5200);
DISPLAY 0.510638 (-6750 5200);
PAINT SKYBLUE (-6750 5200);
FORCEPROP 1 LAST PACK_TYPE 0402LF
J 0
(-7000 5100);
DISPLAY 0.510638 (-7000 5100);
PAINT SKYBLUE (-7000 5100);
DISPLAY INVISIBLE (-7000 5100);
FORCEPROP 1 LAST WATTAGE 1/16W
J 2
(-6875 5125);
DISPLAY 0.510638 (-6875 5125);
PAINT SKYBLUE (-6875 5125);
DISPLAY INVISIBLE (-6875 5125);
FORCEPROP 1 LAST PART_NUMBER CS03322FB03
J 0
(-7075 5075);
DISPLAY 0.510638 (-7075 5075);
PAINT WHITE (-7075 5075);
DISPLAY INVISIBLE (-7075 5075);
FORCEPROP 1 LAST TOLERANCE 1%
J 0
(-6975 5150);
DISPLAY 0.510638 (-6975 5150);
PAINT SKYBLUE (-6975 5150);
DISPLAY INVISIBLE (-6975 5150);
FORCEPROP 1 LAST PATH I150
J 0
(-7050 5350);
DISPLAY 0.978723 (-7050 5350);
PAINT WHITE (-7050 5350);
DISPLAY INVISIBLE (-7050 5350);
FORCEPROP 2 LAST CDS_LIB pure_quanta
J 0
(-7000 5200);
DISPLAY INVISIBLE (-7000 5200);
FORCEPROP 1 LAST LOCATION R767
J 0
(-7225 5200);
DISPLAY 0.702128 (-7225 5200);
PAINT YELLOW (-7225 5200);
FORCEPROP 1 LASTPIN (-7100 5200) $PN 1
J 0
(-7088 5212);
DISPLAY 0.808511 (-7088 5212);
PAINT WHITE (-7088 5212);
FORCEPROP 1 LASTPIN (-6900 5200) $PN 2
J 0
(-6938 5212);
DISPLAY 0.808511 (-6938 5212);
PAINT WHITE (-6938 5212);
FORCEPROP 2 LAST $SEC 1
J 0
(-7050 5400);
DISPLAY 0.680851 (-7050 5400);
PAINT MONO (-7050 5400);
DISPLAY INVISIBLE (-7050 5400);
FORCEPROP 2 LAST CDS_SEC 1
J 0
(-7050 5400);
DISPLAY 0.680851 (-7050 5400);
DISPLAY INVISIBLE (-7050 5400);
FORCEADD OFFPAGE..1
(-8275 5200);
FORCEPROP 2 LAST $XR1 15 
J 0
(-8616 5200);
DISPLAY 0.638298 (-8616 5200);
PAINT MONO (-8616 5200);
FORCEPROP 2 LAST $XR0 46 
J 0
(-8526 5200);
DISPLAY 0.638298 (-8526 5200);
PAINT MONO (-8526 5200);
FORCEPROP 2 LAST PATH I151
J 0
(-8525 5250);
DISPLAY 0.680851 (-8525 5250);
DISPLAY INVISIBLE (-8525 5250);
FORCEPROP 2 LAST CDS_LIB standard
J 0
(-8275 5200);
DISPLAY INVISIBLE (-8275 5200);
FORCEPROP 1 LAST OFFPAGE TRUE
J 0
(-7950 5075);
DISPLAY 0.872340 (-7950 5075);
PAINT GREEN (-7950 5075);
DISPLAY INVISIBLE (-7950 5075);
FORCEPROP 1 LAST COMMENT_BODY TRUE
J 0
(-8150 5100);
DISPLAY 0.872340 (-8150 5100);
PAINT PEACH (-8150 5100);
DISPLAY INVISIBLE (-8150 5100);
FORCEADD OFFPAGE..1
(-8275 5150);
FORCEPROP 2 LAST $XR0 46 
J 0
(-8526 5150);
DISPLAY 0.638298 (-8526 5150);
PAINT MONO (-8526 5150);
FORCEPROP 2 LAST $XR1 15 
J 0
(-8616 5150);
DISPLAY 0.638298 (-8616 5150);
PAINT MONO (-8616 5150);
FORCEPROP 2 LAST CDS_LIB standard
J 0
(-8275 5150);
DISPLAY INVISIBLE (-8275 5150);
FORCEPROP 1 LAST OFFPAGE TRUE
J 0
(-7950 5025);
DISPLAY 0.872340 (-7950 5025);
PAINT GREEN (-7950 5025);
DISPLAY INVISIBLE (-7950 5025);
FORCEPROP 1 LAST COMMENT_BODY TRUE
J 0
(-8150 5050);
DISPLAY 0.872340 (-8150 5050);
PAINT PEACH (-8150 5050);
DISPLAY INVISIBLE (-8150 5050);
FORCEPROP 2 LAST PATH I152
J 0
(-8525 5200);
DISPLAY 0.680851 (-8525 5200);
DISPLAY INVISIBLE (-8525 5200);
FORCEADD OFFPAGE..1
(-8275 4650);
FORCEPROP 2 LAST $XR1 15 
J 0
(-8616 4650);
DISPLAY 0.638298 (-8616 4650);
PAINT MONO (-8616 4650);
FORCEPROP 2 LAST $XR0 21 
J 0
(-8526 4650);
DISPLAY 0.638298 (-8526 4650);
PAINT MONO (-8526 4650);
FORCEPROP 1 LAST COMMENT_BODY TRUE
J 0
(-8150 4550);
DISPLAY 0.872340 (-8150 4550);
PAINT PEACH (-8150 4550);
DISPLAY INVISIBLE (-8150 4550);
FORCEPROP 1 LAST OFFPAGE TRUE
J 0
(-7950 4525);
DISPLAY 0.872340 (-7950 4525);
PAINT GREEN (-7950 4525);
DISPLAY INVISIBLE (-7950 4525);
FORCEPROP 2 LAST CDS_LIB standard
J 0
(-8275 4650);
DISPLAY INVISIBLE (-8275 4650);
FORCEPROP 2 LAST PATH I153
J 0
(-8525 4700);
DISPLAY 0.680851 (-8525 4700);
DISPLAY INVISIBLE (-8525 4700);
FORCEADD Q_RES..1
(-2725 5250);
FORCEPROP 1 LAST MATERIAL CHIP
J 2
(-2400 5250);
DISPLAY 0.510638 (-2400 5250);
PAINT SKYBLUE (-2400 5250);
FORCEPROP 1 LAST VALUE 0
J 2
(-2575 5250);
DISPLAY 0.510638 (-2575 5250);
PAINT SKYBLUE (-2575 5250);
FORCEPROP 1 LAST PART_NUMBER CS00002JB13
J 0
(-2825 5325);
DISPLAY 0.510638 (-2825 5325);
PAINT WHITE (-2825 5325);
DISPLAY INVISIBLE (-2825 5325);
FORCEPROP 1 LAST PACK_TYPE 0402LF
J 0
(-2750 5300);
DISPLAY 0.510638 (-2750 5300);
PAINT SKYBLUE (-2750 5300);
DISPLAY INVISIBLE (-2750 5300);
FORCEPROP 1 LAST WATTAGE 1/16W
J 2
(-2375 5350);
DISPLAY 0.510638 (-2375 5350);
PAINT SKYBLUE (-2375 5350);
DISPLAY INVISIBLE (-2375 5350);
FORCEPROP 1 LAST TOLERANCE 5%
J 0
(-2800 5350);
DISPLAY 0.510638 (-2800 5350);
PAINT SKYBLUE (-2800 5350);
DISPLAY INVISIBLE (-2800 5350);
FORCEPROP 1 LAST PATH I155
J 0
(-2775 5400);
DISPLAY 0.978723 (-2775 5400);
PAINT WHITE (-2775 5400);
DISPLAY INVISIBLE (-2775 5400);
FORCEPROP 2 LAST SEC_TYPE 0402LF
J 0
(-2775 5450);
DISPLAY 1.021277 (-2775 5450);
DISPLAY INVISIBLE (-2775 5450);
FORCEPROP 2 LAST CDS_LIB pure_quanta
J 0
(-2725 5250);
DISPLAY INVISIBLE (-2725 5250);
FORCEPROP 1 LAST $LOCATION R10
J 0
(-3000 5250);
DISPLAY 0.702128 (-3000 5250);
PAINT YELLOW (-3000 5250);
FORCEPROP 1 LASTPIN (-2825 5250) $PN 1
J 0
(-2813 5262);
DISPLAY 0.808511 (-2813 5262);
PAINT WHITE (-2813 5262);
FORCEPROP 1 LASTPIN (-2625 5250) $PN 2
J 0
(-2663 5262);
DISPLAY 0.808511 (-2663 5262);
PAINT WHITE (-2663 5262);
FORCEPROP 0 LAST CDS_LOCATION R10
J 0
(-3000 5300);
DISPLAY 0.680851 (-3000 5300);
DISPLAY INVISIBLE (-3000 5300);
FORCEPROP 0 LAST SEC 1
J 0
(-2875 5300);
DISPLAY 0.680851 (-2875 5300);
PAINT MONO (-2875 5300);
DISPLAY INVISIBLE (-2875 5300);
FORCEADD Q_RES..1
(-7000 5150);
FORCEPROP 1 LAST VALUE 33.2
J 2
(-6775 5150);
DISPLAY 0.510638 (-6775 5150);
PAINT SKYBLUE (-6775 5150);
FORCEPROP 1 LAST MATERIAL CHIP
J 0
(-6750 5150);
DISPLAY 0.510638 (-6750 5150);
PAINT SKYBLUE (-6750 5150);
FORCEPROP 2 LAST CDS_LIB pure_quanta
J 0
(-7000 5150);
DISPLAY INVISIBLE (-7000 5150);
FORCEPROP 1 LAST PATH I156
J 0
(-7050 5300);
DISPLAY 0.978723 (-7050 5300);
PAINT WHITE (-7050 5300);
DISPLAY INVISIBLE (-7050 5300);
FORCEPROP 1 LAST PACK_TYPE 0402LF
J 0
(-7000 5050);
DISPLAY 0.510638 (-7000 5050);
PAINT SKYBLUE (-7000 5050);
DISPLAY INVISIBLE (-7000 5050);
FORCEPROP 1 LAST WATTAGE 1/16W
J 2
(-6875 5075);
DISPLAY 0.510638 (-6875 5075);
PAINT SKYBLUE (-6875 5075);
DISPLAY INVISIBLE (-6875 5075);
FORCEPROP 1 LAST PART_NUMBER CS03322FB03
J 0
(-7075 5025);
DISPLAY 0.510638 (-7075 5025);
PAINT WHITE (-7075 5025);
DISPLAY INVISIBLE (-7075 5025);
FORCEPROP 1 LAST TOLERANCE 1%
J 0
(-6975 5100);
DISPLAY 0.510638 (-6975 5100);
PAINT SKYBLUE (-6975 5100);
DISPLAY INVISIBLE (-6975 5100);
FORCEPROP 1 LAST LOCATION R123
J 0
(-7225 5150);
DISPLAY 0.702128 (-7225 5150);
PAINT YELLOW (-7225 5150);
FORCEPROP 1 LASTPIN (-7100 5150) $PN 1
J 0
(-7088 5162);
DISPLAY 0.787234 (-7088 5162);
PAINT MONO (-7088 5162);
FORCEPROP 1 LASTPIN (-6900 5150) $PN 2
J 0
(-6938 5162);
DISPLAY 0.787234 (-6938 5162);
PAINT MONO (-6938 5162);
FORCEPROP 0 LAST $SEC 1
J 0
(-7225 5200);
DISPLAY 0.680851 (-7225 5200);
PAINT MONO (-7225 5200);
DISPLAY INVISIBLE (-7225 5200);
FORCEPROP 0 LAST CDS_SEC 1
J 0
(-7225 5200);
DISPLAY 0.680851 (-7225 5200);
DISPLAY INVISIBLE (-7225 5200);
FORCEADD Q_RES..1
(-7000 4950);
FORCEPROP 1 LAST MATERIAL CHIP
J 0
(-6750 4950);
DISPLAY 0.510638 (-6750 4950);
PAINT SKYBLUE (-6750 4950);
FORCEPROP 1 LAST VALUE 33.2
J 2
(-6775 4950);
DISPLAY 0.510638 (-6775 4950);
PAINT SKYBLUE (-6775 4950);
FORCEPROP 2 LAST CDS_LIB pure_quanta
J 0
(-7000 4950);
DISPLAY INVISIBLE (-7000 4950);
FORCEPROP 1 LAST PATH I157
J 0
(-7050 5100);
DISPLAY 0.978723 (-7050 5100);
PAINT WHITE (-7050 5100);
DISPLAY INVISIBLE (-7050 5100);
FORCEPROP 1 LAST PACK_TYPE 0402LF
J 0
(-7000 4850);
DISPLAY 0.510638 (-7000 4850);
PAINT SKYBLUE (-7000 4850);
DISPLAY INVISIBLE (-7000 4850);
FORCEPROP 1 LAST WATTAGE 1/16W
J 2
(-6875 4875);
DISPLAY 0.510638 (-6875 4875);
PAINT SKYBLUE (-6875 4875);
DISPLAY INVISIBLE (-6875 4875);
FORCEPROP 1 LAST PART_NUMBER CS03322FB03
J 0
(-7075 4825);
DISPLAY 0.510638 (-7075 4825);
PAINT WHITE (-7075 4825);
DISPLAY INVISIBLE (-7075 4825);
FORCEPROP 1 LAST TOLERANCE 1%
J 0
(-6975 4900);
DISPLAY 0.510638 (-6975 4900);
PAINT SKYBLUE (-6975 4900);
DISPLAY INVISIBLE (-6975 4900);
FORCEPROP 1 LAST LOCATION R718
J 0
(-7225 4950);
DISPLAY 0.702128 (-7225 4950);
PAINT YELLOW (-7225 4950);
FORCEPROP 1 LASTPIN (-7100 4950) $PN 1
J 0
(-7088 4962);
DISPLAY 0.787234 (-7088 4962);
PAINT MONO (-7088 4962);
FORCEPROP 1 LASTPIN (-6900 4950) $PN 2
J 0
(-6938 4962);
DISPLAY 0.787234 (-6938 4962);
PAINT MONO (-6938 4962);
FORCEPROP 0 LAST $SEC 1
J 0
(-7225 5000);
DISPLAY 0.680851 (-7225 5000);
PAINT MONO (-7225 5000);
DISPLAY INVISIBLE (-7225 5000);
FORCEPROP 0 LAST CDS_SEC 1
J 0
(-7225 5000);
DISPLAY 0.680851 (-7225 5000);
DISPLAY INVISIBLE (-7225 5000);
FORCEADD Q_RES..1
(-7000 4900);
FORCEPROP 1 LAST VALUE 33.2
J 2
(-6775 4900);
DISPLAY 0.510638 (-6775 4900);
PAINT SKYBLUE (-6775 4900);
FORCEPROP 1 LAST MATERIAL CHIP
J 0
(-6750 4900);
DISPLAY 0.510638 (-6750 4900);
PAINT SKYBLUE (-6750 4900);
FORCEPROP 2 LAST CDS_LIB pure_quanta
J 0
(-7000 4900);
DISPLAY INVISIBLE (-7000 4900);
FORCEPROP 1 LAST PATH I158
J 0
(-7050 5050);
DISPLAY 0.978723 (-7050 5050);
PAINT WHITE (-7050 5050);
DISPLAY INVISIBLE (-7050 5050);
FORCEPROP 1 LAST PACK_TYPE 0402LF
J 0
(-7000 4800);
DISPLAY 0.510638 (-7000 4800);
PAINT SKYBLUE (-7000 4800);
DISPLAY INVISIBLE (-7000 4800);
FORCEPROP 1 LAST WATTAGE 1/16W
J 2
(-6875 4825);
DISPLAY 0.510638 (-6875 4825);
PAINT SKYBLUE (-6875 4825);
DISPLAY INVISIBLE (-6875 4825);
FORCEPROP 1 LAST PART_NUMBER CS03322FB03
J 0
(-7075 4775);
DISPLAY 0.510638 (-7075 4775);
PAINT WHITE (-7075 4775);
DISPLAY INVISIBLE (-7075 4775);
FORCEPROP 1 LAST TOLERANCE 1%
J 0
(-6975 4850);
DISPLAY 0.510638 (-6975 4850);
PAINT SKYBLUE (-6975 4850);
DISPLAY INVISIBLE (-6975 4850);
FORCEPROP 1 LAST LOCATION R837
J 0
(-7225 4900);
DISPLAY 0.702128 (-7225 4900);
PAINT YELLOW (-7225 4900);
FORCEPROP 1 LASTPIN (-7100 4900) $PN 1
J 0
(-7088 4912);
DISPLAY 0.787234 (-7088 4912);
PAINT MONO (-7088 4912);
FORCEPROP 1 LASTPIN (-6900 4900) $PN 2
J 0
(-6938 4912);
DISPLAY 0.787234 (-6938 4912);
PAINT MONO (-6938 4912);
FORCEPROP 0 LAST $SEC 1
J 0
(-7225 4950);
DISPLAY 0.680851 (-7225 4950);
PAINT MONO (-7225 4950);
DISPLAY INVISIBLE (-7225 4950);
FORCEPROP 0 LAST CDS_SEC 1
J 0
(-7225 4950);
DISPLAY 0.680851 (-7225 4950);
DISPLAY INVISIBLE (-7225 4950);
FORCEADD Q_RES..1
(-7000 4650);
FORCEPROP 1 LAST MATERIAL CHIP
J 0
(-6750 4650);
DISPLAY 0.510638 (-6750 4650);
PAINT SKYBLUE (-6750 4650);
FORCEPROP 1 LAST VALUE 33.2
J 2
(-6775 4650);
DISPLAY 0.510638 (-6775 4650);
PAINT SKYBLUE (-6775 4650);
FORCEPROP 2 LAST CDS_LIB pure_quanta
J 0
(-7000 4650);
DISPLAY INVISIBLE (-7000 4650);
FORCEPROP 1 LAST PATH I159
J 0
(-7050 4800);
DISPLAY 0.978723 (-7050 4800);
PAINT WHITE (-7050 4800);
DISPLAY INVISIBLE (-7050 4800);
FORCEPROP 1 LAST PACK_TYPE 0402LF
J 0
(-7000 4550);
DISPLAY 0.510638 (-7000 4550);
PAINT SKYBLUE (-7000 4550);
DISPLAY INVISIBLE (-7000 4550);
FORCEPROP 1 LAST WATTAGE 1/16W
J 2
(-6875 4575);
DISPLAY 0.510638 (-6875 4575);
PAINT SKYBLUE (-6875 4575);
DISPLAY INVISIBLE (-6875 4575);
FORCEPROP 1 LAST PART_NUMBER CS03322FB03
J 0
(-7075 4525);
DISPLAY 0.510638 (-7075 4525);
PAINT WHITE (-7075 4525);
DISPLAY INVISIBLE (-7075 4525);
FORCEPROP 1 LAST TOLERANCE 1%
J 0
(-6975 4600);
DISPLAY 0.510638 (-6975 4600);
PAINT SKYBLUE (-6975 4600);
DISPLAY INVISIBLE (-6975 4600);
FORCEPROP 1 LAST LOCATION R459
J 0
(-7225 4650);
DISPLAY 0.702128 (-7225 4650);
PAINT YELLOW (-7225 4650);
FORCEPROP 1 LASTPIN (-7100 4650) $PN 1
J 0
(-7088 4662);
DISPLAY 0.787234 (-7088 4662);
PAINT MONO (-7088 4662);
FORCEPROP 1 LASTPIN (-6900 4650) $PN 2
J 0
(-6938 4662);
DISPLAY 0.787234 (-6938 4662);
PAINT MONO (-6938 4662);
FORCEPROP 0 LAST $SEC 1
J 0
(-7225 4700);
DISPLAY 0.680851 (-7225 4700);
PAINT MONO (-7225 4700);
DISPLAY INVISIBLE (-7225 4700);
FORCEPROP 0 LAST CDS_SEC 1
J 0
(-7225 4700);
DISPLAY 0.680851 (-7225 4700);
DISPLAY INVISIBLE (-7225 4700);
FORCEADD OFFPAGE..1
(-8275 4100);
FORCEPROP 2 LAST $XR0 15 
J 0
(-8526 4100);
DISPLAY 0.638298 (-8526 4100);
PAINT MONO (-8526 4100);
FORCEPROP 2 LAST PATH I16
J 0
(-8475 4150);
DISPLAY 0.680851 (-8475 4150);
DISPLAY INVISIBLE (-8475 4150);
FORCEPROP 2 LAST CDS_LIB standard
J 0
(-8275 4100);
DISPLAY INVISIBLE (-8275 4100);
FORCEPROP 1 LAST OFFPAGE TRUE
J 0
(-7950 3975);
DISPLAY 0.851064 (-7950 3975);
PAINT GREEN (-7950 3975);
DISPLAY INVISIBLE (-7950 3975);
FORCEPROP 1 LAST COMMENT_BODY TRUE
J 0
(-8150 4000);
DISPLAY 0.851064 (-8150 4000);
PAINT PEACH (-8150 4000);
DISPLAY INVISIBLE (-8150 4000);
FORCEADD Q_RES..1
(-2550 3850);
FORCEPROP 1 LAST VALUE 33.2
J 2
(-2325 3850);
DISPLAY 0.510638 (-2325 3850);
PAINT SKYBLUE (-2325 3850);
FORCEPROP 1 LAST MATERIAL CHIP
J 0
(-2300 3850);
DISPLAY 0.510638 (-2300 3850);
PAINT SKYBLUE (-2300 3850);
FORCEPROP 2 LAST CDS_LIB pure_quanta
J 0
(-2550 3850);
DISPLAY INVISIBLE (-2550 3850);
FORCEPROP 1 LAST PATH I160
J 0
(-2600 4000);
DISPLAY 0.978723 (-2600 4000);
PAINT WHITE (-2600 4000);
DISPLAY INVISIBLE (-2600 4000);
FORCEPROP 1 LAST TOLERANCE 1%
J 0
(-2525 3800);
DISPLAY 0.510638 (-2525 3800);
PAINT SKYBLUE (-2525 3800);
DISPLAY INVISIBLE (-2525 3800);
FORCEPROP 1 LAST PART_NUMBER CS03322FB03
J 0
(-2625 3725);
DISPLAY 0.510638 (-2625 3725);
PAINT WHITE (-2625 3725);
DISPLAY INVISIBLE (-2625 3725);
FORCEPROP 1 LAST WATTAGE 1/16W
J 2
(-2425 3775);
DISPLAY 0.510638 (-2425 3775);
PAINT SKYBLUE (-2425 3775);
DISPLAY INVISIBLE (-2425 3775);
FORCEPROP 1 LAST PACK_TYPE 0402LF
J 0
(-2550 3750);
DISPLAY 0.510638 (-2550 3750);
PAINT SKYBLUE (-2550 3750);
DISPLAY INVISIBLE (-2550 3750);
FORCEPROP 1 LAST LOCATION R434
J 0
(-2775 3850);
DISPLAY 0.702128 (-2775 3850);
PAINT YELLOW (-2775 3850);
FORCEPROP 1 LASTPIN (-2650 3850) $PN 1
J 0
(-2638 3862);
DISPLAY 0.787234 (-2638 3862);
PAINT MONO (-2638 3862);
FORCEPROP 1 LASTPIN (-2450 3850) $PN 2
J 0
(-2488 3862);
DISPLAY 0.787234 (-2488 3862);
PAINT MONO (-2488 3862);
FORCEPROP 0 LAST $SEC 1
J 0
(-2775 3900);
DISPLAY 0.680851 (-2775 3900);
PAINT MONO (-2775 3900);
DISPLAY INVISIBLE (-2775 3900);
FORCEPROP 0 LAST CDS_SEC 1
J 0
(-2775 3900);
DISPLAY 0.680851 (-2775 3900);
DISPLAY INVISIBLE (-2775 3900);
FORCEADD Q_RES..1
(-2550 3750);
FORCEPROP 1 LAST MATERIAL CHIP
J 0
(-2300 3750);
DISPLAY 0.510638 (-2300 3750);
PAINT SKYBLUE (-2300 3750);
FORCEPROP 1 LAST VALUE 33.2
J 2
(-2325 3750);
DISPLAY 0.510638 (-2325 3750);
PAINT SKYBLUE (-2325 3750);
FORCEPROP 2 LAST CDS_LIB pure_quanta
J 0
(-2550 3750);
DISPLAY INVISIBLE (-2550 3750);
FORCEPROP 1 LAST PATH I161
J 0
(-2600 3900);
DISPLAY 0.978723 (-2600 3900);
PAINT WHITE (-2600 3900);
DISPLAY INVISIBLE (-2600 3900);
FORCEPROP 1 LAST PACK_TYPE 0402LF
J 0
(-2550 3650);
DISPLAY 0.510638 (-2550 3650);
PAINT SKYBLUE (-2550 3650);
DISPLAY INVISIBLE (-2550 3650);
FORCEPROP 1 LAST WATTAGE 1/16W
J 2
(-2425 3675);
DISPLAY 0.510638 (-2425 3675);
PAINT SKYBLUE (-2425 3675);
DISPLAY INVISIBLE (-2425 3675);
FORCEPROP 1 LAST PART_NUMBER CS03322FB03
J 0
(-2625 3625);
DISPLAY 0.510638 (-2625 3625);
PAINT WHITE (-2625 3625);
DISPLAY INVISIBLE (-2625 3625);
FORCEPROP 1 LAST TOLERANCE 1%
J 0
(-2525 3700);
DISPLAY 0.510638 (-2525 3700);
PAINT SKYBLUE (-2525 3700);
DISPLAY INVISIBLE (-2525 3700);
FORCEPROP 1 LAST LOCATION R435
J 0
(-2775 3750);
DISPLAY 0.702128 (-2775 3750);
PAINT YELLOW (-2775 3750);
FORCEPROP 1 LASTPIN (-2650 3750) $PN 1
J 0
(-2638 3762);
DISPLAY 0.787234 (-2638 3762);
PAINT MONO (-2638 3762);
FORCEPROP 1 LASTPIN (-2450 3750) $PN 2
J 0
(-2488 3762);
DISPLAY 0.787234 (-2488 3762);
PAINT MONO (-2488 3762);
FORCEPROP 0 LAST $SEC 1
J 0
(-2775 3800);
DISPLAY 0.680851 (-2775 3800);
PAINT MONO (-2775 3800);
DISPLAY INVISIBLE (-2775 3800);
FORCEPROP 0 LAST CDS_SEC 1
J 0
(-2775 3800);
DISPLAY 0.680851 (-2775 3800);
DISPLAY INVISIBLE (-2775 3800);
FORCEADD Q_RES..1
(-2550 3700);
FORCEPROP 1 LAST MATERIAL CHIP
J 0
(-2300 3700);
DISPLAY 0.510638 (-2300 3700);
PAINT SKYBLUE (-2300 3700);
FORCEPROP 1 LAST VALUE 33.2
J 2
(-2325 3700);
DISPLAY 0.510638 (-2325 3700);
PAINT SKYBLUE (-2325 3700);
FORCEPROP 2 LAST CDS_LIB pure_quanta
J 0
(-2550 3700);
DISPLAY INVISIBLE (-2550 3700);
FORCEPROP 1 LAST PATH I162
J 0
(-2600 3850);
DISPLAY 0.978723 (-2600 3850);
PAINT WHITE (-2600 3850);
DISPLAY INVISIBLE (-2600 3850);
FORCEPROP 1 LAST PACK_TYPE 0402LF
J 0
(-2550 3600);
DISPLAY 0.510638 (-2550 3600);
PAINT SKYBLUE (-2550 3600);
DISPLAY INVISIBLE (-2550 3600);
FORCEPROP 1 LAST WATTAGE 1/16W
J 2
(-2425 3625);
DISPLAY 0.510638 (-2425 3625);
PAINT SKYBLUE (-2425 3625);
DISPLAY INVISIBLE (-2425 3625);
FORCEPROP 1 LAST PART_NUMBER CS03322FB03
J 0
(-2625 3575);
DISPLAY 0.510638 (-2625 3575);
PAINT WHITE (-2625 3575);
DISPLAY INVISIBLE (-2625 3575);
FORCEPROP 1 LAST TOLERANCE 1%
J 0
(-2525 3650);
DISPLAY 0.510638 (-2525 3650);
PAINT SKYBLUE (-2525 3650);
DISPLAY INVISIBLE (-2525 3650);
FORCEPROP 1 LAST LOCATION R436
J 0
(-2775 3700);
DISPLAY 0.702128 (-2775 3700);
PAINT YELLOW (-2775 3700);
FORCEPROP 1 LASTPIN (-2650 3700) $PN 1
J 0
(-2638 3712);
DISPLAY 0.787234 (-2638 3712);
PAINT MONO (-2638 3712);
FORCEPROP 1 LASTPIN (-2450 3700) $PN 2
J 0
(-2488 3712);
DISPLAY 0.787234 (-2488 3712);
PAINT MONO (-2488 3712);
FORCEPROP 0 LAST $SEC 1
J 0
(-2775 3750);
DISPLAY 0.680851 (-2775 3750);
PAINT MONO (-2775 3750);
DISPLAY INVISIBLE (-2775 3750);
FORCEPROP 0 LAST CDS_SEC 1
J 0
(-2775 3750);
DISPLAY 0.680851 (-2775 3750);
DISPLAY INVISIBLE (-2775 3750);
FORCEADD Q_RES..1
(-2550 3600);
FORCEPROP 1 LAST MATERIAL CHIP
J 0
(-2300 3600);
DISPLAY 0.510638 (-2300 3600);
PAINT SKYBLUE (-2300 3600);
FORCEPROP 1 LAST VALUE 33.2
J 2
(-2325 3600);
DISPLAY 0.510638 (-2325 3600);
PAINT SKYBLUE (-2325 3600);
FORCEPROP 2 LAST CDS_LIB pure_quanta
J 0
(-2550 3600);
DISPLAY INVISIBLE (-2550 3600);
FORCEPROP 1 LAST PATH I163
J 0
(-2600 3750);
DISPLAY 0.978723 (-2600 3750);
PAINT WHITE (-2600 3750);
DISPLAY INVISIBLE (-2600 3750);
FORCEPROP 1 LAST PACK_TYPE 0402LF
J 0
(-2550 3500);
DISPLAY 0.510638 (-2550 3500);
PAINT SKYBLUE (-2550 3500);
DISPLAY INVISIBLE (-2550 3500);
FORCEPROP 1 LAST WATTAGE 1/16W
J 2
(-2425 3525);
DISPLAY 0.510638 (-2425 3525);
PAINT SKYBLUE (-2425 3525);
DISPLAY INVISIBLE (-2425 3525);
FORCEPROP 1 LAST PART_NUMBER CS03322FB03
J 0
(-2625 3475);
DISPLAY 0.510638 (-2625 3475);
PAINT WHITE (-2625 3475);
DISPLAY INVISIBLE (-2625 3475);
FORCEPROP 1 LAST TOLERANCE 1%
J 0
(-2525 3550);
DISPLAY 0.510638 (-2525 3550);
PAINT SKYBLUE (-2525 3550);
DISPLAY INVISIBLE (-2525 3550);
FORCEPROP 1 LAST LOCATION R437
J 0
(-2775 3600);
DISPLAY 0.702128 (-2775 3600);
PAINT YELLOW (-2775 3600);
FORCEPROP 1 LASTPIN (-2650 3600) $PN 1
J 0
(-2638 3612);
DISPLAY 0.787234 (-2638 3612);
PAINT MONO (-2638 3612);
FORCEPROP 1 LASTPIN (-2450 3600) $PN 2
J 0
(-2488 3612);
DISPLAY 0.787234 (-2488 3612);
PAINT MONO (-2488 3612);
FORCEPROP 0 LAST $SEC 1
J 0
(-2775 3650);
DISPLAY 0.680851 (-2775 3650);
PAINT MONO (-2775 3650);
DISPLAY INVISIBLE (-2775 3650);
FORCEPROP 0 LAST CDS_SEC 1
J 0
(-2775 3650);
DISPLAY 0.680851 (-2775 3650);
DISPLAY INVISIBLE (-2775 3650);
FORCEADD Q_RES..1
(-2550 4600);
FORCEPROP 1 LAST MATERIAL CHIP
J 0
(-2300 4600);
DISPLAY 0.510638 (-2300 4600);
PAINT SKYBLUE (-2300 4600);
FORCEPROP 1 LAST VALUE 33.2
J 2
(-2325 4600);
DISPLAY 0.510638 (-2325 4600);
PAINT SKYBLUE (-2325 4600);
FORCEPROP 2 LAST CDS_LIB pure_quanta
J 0
(-2550 4600);
DISPLAY INVISIBLE (-2550 4600);
FORCEPROP 1 LAST PATH I164
J 0
(-2600 4750);
DISPLAY 0.978723 (-2600 4750);
PAINT WHITE (-2600 4750);
DISPLAY INVISIBLE (-2600 4750);
FORCEPROP 1 LAST PACK_TYPE 0402LF
J 0
(-2550 4500);
DISPLAY 0.510638 (-2550 4500);
PAINT SKYBLUE (-2550 4500);
DISPLAY INVISIBLE (-2550 4500);
FORCEPROP 1 LAST WATTAGE 1/16W
J 2
(-2425 4525);
DISPLAY 0.510638 (-2425 4525);
PAINT SKYBLUE (-2425 4525);
DISPLAY INVISIBLE (-2425 4525);
FORCEPROP 1 LAST PART_NUMBER CS03322FB03
J 0
(-2625 4475);
DISPLAY 0.510638 (-2625 4475);
PAINT WHITE (-2625 4475);
DISPLAY INVISIBLE (-2625 4475);
FORCEPROP 1 LAST TOLERANCE 1%
J 0
(-2525 4550);
DISPLAY 0.510638 (-2525 4550);
PAINT SKYBLUE (-2525 4550);
DISPLAY INVISIBLE (-2525 4550);
FORCEPROP 1 LAST LOCATION R270
J 0
(-2775 4600);
DISPLAY 0.702128 (-2775 4600);
PAINT YELLOW (-2775 4600);
FORCEPROP 1 LASTPIN (-2650 4600) $PN 1
J 0
(-2638 4612);
DISPLAY 0.787234 (-2638 4612);
PAINT MONO (-2638 4612);
FORCEPROP 1 LASTPIN (-2450 4600) $PN 2
J 0
(-2488 4612);
DISPLAY 0.787234 (-2488 4612);
PAINT MONO (-2488 4612);
FORCEPROP 0 LAST $SEC 1
J 0
(-2775 4650);
DISPLAY 0.680851 (-2775 4650);
PAINT MONO (-2775 4650);
DISPLAY INVISIBLE (-2775 4650);
FORCEPROP 0 LAST CDS_SEC 1
J 0
(-2775 4650);
DISPLAY 0.680851 (-2775 4650);
DISPLAY INVISIBLE (-2775 4650);
FORCEADD Q_RES..1
(-2725 5100);
FORCEPROP 1 LAST MATERIAL CHIP
J 2
(-2400 5100);
DISPLAY 0.510638 (-2400 5100);
PAINT SKYBLUE (-2400 5100);
FORCEPROP 1 LAST VALUE 0
J 2
(-2575 5100);
DISPLAY 0.510638 (-2575 5100);
PAINT SKYBLUE (-2575 5100);
FORCEPROP 1 LAST TOLERANCE 5%
J 0
(-2800 5200);
DISPLAY 0.510638 (-2800 5200);
PAINT SKYBLUE (-2800 5200);
DISPLAY INVISIBLE (-2800 5200);
FORCEPROP 1 LAST WATTAGE 1/16W
J 2
(-2375 5200);
DISPLAY 0.510638 (-2375 5200);
PAINT SKYBLUE (-2375 5200);
DISPLAY INVISIBLE (-2375 5200);
FORCEPROP 1 LAST PACK_TYPE 0402LF
J 0
(-2750 5150);
DISPLAY 0.510638 (-2750 5150);
PAINT SKYBLUE (-2750 5150);
DISPLAY INVISIBLE (-2750 5150);
FORCEPROP 1 LAST PART_NUMBER CS00002JB13
J 0
(-2825 5175);
DISPLAY 0.510638 (-2825 5175);
PAINT WHITE (-2825 5175);
DISPLAY INVISIBLE (-2825 5175);
FORCEPROP 1 LAST PATH I165
J 0
(-2775 5250);
DISPLAY 0.978723 (-2775 5250);
PAINT WHITE (-2775 5250);
DISPLAY INVISIBLE (-2775 5250);
FORCEPROP 2 LAST CDS_LIB pure_quanta
J 0
(-2725 5100);
DISPLAY INVISIBLE (-2725 5100);
FORCEPROP 1 LAST LOCATION R272
J 0
(-2975 5100);
DISPLAY 0.638298 (-2975 5100);
FORCEPROP 1 LASTPIN (-2825 5100) $PN 1
J 0
(-2813 5112);
DISPLAY 0.787234 (-2813 5112);
PAINT MONO (-2813 5112);
FORCEPROP 1 LASTPIN (-2625 5100) $PN 2
J 0
(-2663 5112);
DISPLAY 0.787234 (-2663 5112);
PAINT MONO (-2663 5112);
FORCEPROP 0 LAST $SEC 1
J 0
(-2975 5150);
DISPLAY 0.680851 (-2975 5150);
PAINT MONO (-2975 5150);
DISPLAY INVISIBLE (-2975 5150);
FORCEPROP 0 LAST CDS_SEC 1
J 0
(-2975 5150);
DISPLAY 0.680851 (-2975 5150);
DISPLAY INVISIBLE (-2975 5150);
FORCEADD Q_RES..1
(-2725 5050);
FORCEPROP 1 LAST MATERIAL CHIP
J 2
(-2400 5050);
DISPLAY 0.510638 (-2400 5050);
PAINT SKYBLUE (-2400 5050);
FORCEPROP 1 LAST VALUE 0
J 2
(-2575 5050);
DISPLAY 0.510638 (-2575 5050);
PAINT SKYBLUE (-2575 5050);
FORCEPROP 2 LAST CDS_LIB pure_quanta
J 0
(-2725 5050);
DISPLAY INVISIBLE (-2725 5050);
FORCEPROP 1 LAST PATH I166
J 0
(-2775 5200);
DISPLAY 0.978723 (-2775 5200);
PAINT WHITE (-2775 5200);
DISPLAY INVISIBLE (-2775 5200);
FORCEPROP 1 LAST PART_NUMBER CS00002JB13
J 0
(-2825 5125);
DISPLAY 0.510638 (-2825 5125);
PAINT WHITE (-2825 5125);
DISPLAY INVISIBLE (-2825 5125);
FORCEPROP 1 LAST PACK_TYPE 0402LF
J 0
(-2750 5100);
DISPLAY 0.510638 (-2750 5100);
PAINT SKYBLUE (-2750 5100);
DISPLAY INVISIBLE (-2750 5100);
FORCEPROP 1 LAST WATTAGE 1/16W
J 2
(-2375 5150);
DISPLAY 0.510638 (-2375 5150);
PAINT SKYBLUE (-2375 5150);
DISPLAY INVISIBLE (-2375 5150);
FORCEPROP 1 LAST TOLERANCE 5%
J 0
(-2800 5150);
DISPLAY 0.510638 (-2800 5150);
PAINT SKYBLUE (-2800 5150);
DISPLAY INVISIBLE (-2800 5150);
FORCEPROP 1 LAST LOCATION R303
J 0
(-2975 5050);
DISPLAY 0.638298 (-2975 5050);
FORCEPROP 1 LASTPIN (-2825 5050) $PN 1
J 0
(-2813 5062);
DISPLAY 0.787234 (-2813 5062);
PAINT MONO (-2813 5062);
FORCEPROP 1 LASTPIN (-2625 5050) $PN 2
J 0
(-2663 5062);
DISPLAY 0.787234 (-2663 5062);
PAINT MONO (-2663 5062);
FORCEPROP 0 LAST $SEC 1
J 0
(-2975 5100);
DISPLAY 0.680851 (-2975 5100);
PAINT MONO (-2975 5100);
DISPLAY INVISIBLE (-2975 5100);
FORCEPROP 0 LAST CDS_SEC 1
J 0
(-2975 5100);
DISPLAY 0.680851 (-2975 5100);
DISPLAY INVISIBLE (-2975 5100);
FORCEADD Q_RES..1
(-2550 4500);
FORCEPROP 1 LAST MATERIAL CHIP
J 2
(-2225 4500);
DISPLAY 0.510638 (-2225 4500);
PAINT SKYBLUE (-2225 4500);
FORCEPROP 1 LAST VALUE 0
J 2
(-2400 4500);
DISPLAY 0.510638 (-2400 4500);
PAINT SKYBLUE (-2400 4500);
FORCEPROP 2 LAST CDS_LIB pure_quanta
J 0
(-2550 4500);
DISPLAY INVISIBLE (-2550 4500);
FORCEPROP 1 LAST PATH I167
J 0
(-2600 4650);
DISPLAY 0.978723 (-2600 4650);
PAINT WHITE (-2600 4650);
DISPLAY INVISIBLE (-2600 4650);
FORCEPROP 1 LAST TOLERANCE 5%
J 0
(-2625 4600);
DISPLAY 0.510638 (-2625 4600);
PAINT SKYBLUE (-2625 4600);
DISPLAY INVISIBLE (-2625 4600);
FORCEPROP 1 LAST WATTAGE 1/16W
J 2
(-2200 4600);
DISPLAY 0.510638 (-2200 4600);
PAINT SKYBLUE (-2200 4600);
DISPLAY INVISIBLE (-2200 4600);
FORCEPROP 1 LAST PACK_TYPE 0402LF
J 0
(-2575 4550);
DISPLAY 0.510638 (-2575 4550);
PAINT SKYBLUE (-2575 4550);
DISPLAY INVISIBLE (-2575 4550);
FORCEPROP 1 LAST PART_NUMBER CS00002JB13
J 0
(-2650 4575);
DISPLAY 0.510638 (-2650 4575);
PAINT WHITE (-2650 4575);
DISPLAY INVISIBLE (-2650 4575);
FORCEPROP 1 LAST LOCATION R397
J 0
(-2850 4500);
DISPLAY 0.638298 (-2850 4500);
FORCEPROP 1 LASTPIN (-2650 4500) $PN 1
J 0
(-2638 4512);
DISPLAY 0.787234 (-2638 4512);
PAINT MONO (-2638 4512);
FORCEPROP 1 LASTPIN (-2450 4500) $PN 2
J 0
(-2488 4512);
DISPLAY 0.787234 (-2488 4512);
PAINT MONO (-2488 4512);
FORCEPROP 0 LAST $SEC 1
J 0
(-2850 4550);
DISPLAY 0.680851 (-2850 4550);
PAINT MONO (-2850 4550);
DISPLAY INVISIBLE (-2850 4550);
FORCEPROP 0 LAST CDS_SEC 1
J 0
(-2850 4550);
DISPLAY 0.680851 (-2850 4550);
DISPLAY INVISIBLE (-2850 4550);
FORCEADD Q_RES..1
(-2550 4350);
FORCEPROP 1 LAST VALUE 0
J 2
(-2400 4350);
DISPLAY 0.510638 (-2400 4350);
PAINT SKYBLUE (-2400 4350);
FORCEPROP 1 LAST MATERIAL CHIP
J 2
(-2225 4350);
DISPLAY 0.510638 (-2225 4350);
PAINT SKYBLUE (-2225 4350);
FORCEPROP 2 LAST CDS_LIB pure_quanta
J 0
(-2550 4350);
DISPLAY INVISIBLE (-2550 4350);
FORCEPROP 1 LAST PATH I168
J 0
(-2600 4500);
DISPLAY 0.978723 (-2600 4500);
PAINT WHITE (-2600 4500);
DISPLAY INVISIBLE (-2600 4500);
FORCEPROP 1 LAST TOLERANCE 5%
J 0
(-2625 4450);
DISPLAY 0.510638 (-2625 4450);
PAINT SKYBLUE (-2625 4450);
DISPLAY INVISIBLE (-2625 4450);
FORCEPROP 1 LAST WATTAGE 1/16W
J 2
(-2200 4450);
DISPLAY 0.510638 (-2200 4450);
PAINT SKYBLUE (-2200 4450);
DISPLAY INVISIBLE (-2200 4450);
FORCEPROP 1 LAST PACK_TYPE 0402LF
J 0
(-2575 4400);
DISPLAY 0.510638 (-2575 4400);
PAINT SKYBLUE (-2575 4400);
DISPLAY INVISIBLE (-2575 4400);
FORCEPROP 1 LAST PART_NUMBER CS00002JB13
J 0
(-2650 4425);
DISPLAY 0.510638 (-2650 4425);
PAINT WHITE (-2650 4425);
DISPLAY INVISIBLE (-2650 4425);
FORCEPROP 1 LAST LOCATION R447
J 0
(-2850 4350);
DISPLAY 0.638298 (-2850 4350);
FORCEPROP 1 LASTPIN (-2650 4350) $PN 1
J 0
(-2638 4362);
DISPLAY 0.787234 (-2638 4362);
PAINT MONO (-2638 4362);
FORCEPROP 1 LASTPIN (-2450 4350) $PN 2
J 0
(-2488 4362);
DISPLAY 0.787234 (-2488 4362);
PAINT MONO (-2488 4362);
FORCEPROP 0 LAST $SEC 1
J 0
(-2850 4400);
DISPLAY 0.680851 (-2850 4400);
PAINT MONO (-2850 4400);
DISPLAY INVISIBLE (-2850 4400);
FORCEPROP 0 LAST CDS_SEC 1
J 0
(-2850 4400);
DISPLAY 0.680851 (-2850 4400);
DISPLAY INVISIBLE (-2850 4400);
FORCEADD Q_RES..2
R 2
(-8750 6150);
FORCEPROP 1 LAST MATERIAL CHIP
J 2
(-8800 6075);
DISPLAY 0.510638 (-8800 6075);
PAINT SKYBLUE (-8800 6075);
FORCEPROP 1 LAST TOLERANCE 1%
J 2
(-8800 6125);
DISPLAY 0.510638 (-8800 6125);
PAINT SKYBLUE (-8800 6125);
FORCEPROP 1 LAST VALUE 4.7K
J 2
(-8800 6175);
DISPLAY 0.510638 (-8800 6175);
PAINT SKYBLUE (-8800 6175);
FORCEPROP 1 LAST PACK_TYPE 0402LF
J 2
(-8790 5975);
DISPLAY 0.510638 (-8790 5975);
PAINT SKYBLUE (-8790 5975);
DISPLAY INVISIBLE (-8790 5975);
FORCEPROP 1 LAST WATTAGE 1/16W
J 2
(-8790 6125);
DISPLAY 0.510638 (-8790 6125);
PAINT SKYBLUE (-8790 6125);
DISPLAY INVISIBLE (-8790 6125);
FORCEPROP 2 LAST CDS_LIB pure_quanta
J 2
(-8750 6150);
DISPLAY INVISIBLE (-8750 6150);
FORCEPROP 1 LAST PART_NUMBER CS24702FB06
J 2
(-8790 6025);
DISPLAY 0.510638 (-8790 6025);
PAINT WHITE (-8790 6025);
DISPLAY INVISIBLE (-8790 6025);
FORCEPROP 1 LAST PATH I17
J 2
(-8800 6325);
DISPLAY 0.978723 (-8800 6325);
PAINT WHITE (-8800 6325);
DISPLAY INVISIBLE (-8800 6325);
FORCEPROP 1 LAST LOCATION R625
J 2
(-8800 6225);
DISPLAY 0.702128 (-8800 6225);
PAINT YELLOW (-8800 6225);
FORCEPROP 1 LASTPIN (-8750 6250) $PN 1
J 2
(-8755 6212);
DISPLAY 0.808511 (-8755 6212);
PAINT WHITE (-8755 6212);
FORCEPROP 1 LASTPIN (-8750 6050) $PN 2
J 2
(-8755 6060);
DISPLAY 0.808511 (-8755 6060);
PAINT WHITE (-8755 6060);
FORCEPROP 0 LAST $SEC 1
J 2
(-8800 6325);
DISPLAY 0.680851 (-8800 6325);
PAINT MONO (-8800 6325);
DISPLAY INVISIBLE (-8800 6325);
FORCEPROP 0 LAST CDS_SEC 1
J 2
(-8800 6325);
DISPLAY 0.680851 (-8800 6325);
DISPLAY INVISIBLE (-8800 6325);
FORCEADD VCCAUX15..1
(-8750 6350);
FORCEPROP 3 LASTPIN (-8750 6300) SIG_NAME P3V3_AUX\g
J 0
(-8740 6310);
DISPLAY 0.659574 (-8740 6310);
PAINT MONO (-8740 6310);
DISPLAY INVISIBLE (-8740 6310);
FORCEPROP 1 LAST HDL_POWER P3V3_AUX
J 1
(-8750 6400);
DISPLAY 0.702128 (-8750 6400);
PAINT GREEN (-8750 6400);
FORCEPROP 2 LAST CDS_LIB logical_power
J 0
(-8750 6350);
DISPLAY INVISIBLE (-8750 6350);
FORCEPROP 1 LAST PATH I18
J 0
(-8700 6375);
DISPLAY 0.872340 (-8700 6375);
PAINT AQUA (-8700 6375);
DISPLAY INVISIBLE (-8700 6375);
FORCEADD OFFPAGE..5
(-8275 4450);
FORCEPROP 2 LAST $XR0 15 
J 0
(-8529 4450);
DISPLAY 0.638298 (-8529 4450);
PAINT MONO (-8529 4450);
FORCEPROP 2 LAST PATH I19
J 0
(-8475 4500);
DISPLAY 0.680851 (-8475 4500);
DISPLAY INVISIBLE (-8475 4500);
FORCEPROP 2 LAST CDS_LIB standard
J 0
(-8275 4450);
DISPLAY INVISIBLE (-8275 4450);
FORCEPROP 1 LAST OFFPAGE TRUE
J 0
(-7950 4325);
DISPLAY 0.872340 (-7950 4325);
PAINT GREEN (-7950 4325);
DISPLAY INVISIBLE (-7950 4325);
FORCEPROP 1 LAST COMMENT_BODY TRUE
J 0
(-8175 4375);
DISPLAY 0.872340 (-8175 4375);
PAINT PEACH (-8175 4375);
DISPLAY INVISIBLE (-8175 4375);
FORCEADD OFFPAGE..5
(-8275 4150);
FORCEPROP 2 LAST $XR0 15 
J 0
(-8529 4150);
DISPLAY 0.638298 (-8529 4150);
PAINT MONO (-8529 4150);
FORCEPROP 2 LAST PATH I20
J 0
(-8475 4200);
DISPLAY 0.680851 (-8475 4200);
DISPLAY INVISIBLE (-8475 4200);
FORCEPROP 2 LAST CDS_LIB standard
J 0
(-8275 4150);
DISPLAY INVISIBLE (-8275 4150);
FORCEPROP 1 LAST OFFPAGE TRUE
J 0
(-7950 4025);
DISPLAY 0.872340 (-7950 4025);
PAINT GREEN (-7950 4025);
DISPLAY INVISIBLE (-7950 4025);
FORCEPROP 1 LAST COMMENT_BODY TRUE
J 0
(-8175 4075);
DISPLAY 0.872340 (-8175 4075);
PAINT PEACH (-8175 4075);
DISPLAY INVISIBLE (-8175 4075);
FORCEADD OFFPAGE..5
(-8275 4500);
FORCEPROP 2 LAST $XR0 12 
J 0
(-8529 4500);
DISPLAY 0.638298 (-8529 4500);
PAINT MONO (-8529 4500);
FORCEPROP 2 LAST PATH I21
J 0
(-8475 4550);
DISPLAY 0.680851 (-8475 4550);
DISPLAY INVISIBLE (-8475 4550);
FORCEPROP 2 LAST CDS_LIB standard
J 0
(-8275 4500);
DISPLAY INVISIBLE (-8275 4500);
FORCEPROP 1 LAST OFFPAGE TRUE
J 0
(-7950 4375);
DISPLAY 0.872340 (-7950 4375);
DISPLAY INVISIBLE (-7950 4375);
FORCEPROP 1 LAST COMMENT_BODY TRUE
J 0
(-8175 4425);
DISPLAY 0.872340 (-8175 4425);
PAINT GREEN (-8175 4425);
DISPLAY INVISIBLE (-8175 4425);
FORCEADD OFFPAGE..2
R 2
(-8275 4800);
FORCEPROP 2 LAST $XR1 13 
J 0
(-8619 4800);
DISPLAY 0.638298 (-8619 4800);
PAINT MONO (-8619 4800);
FORCEPROP 2 LAST $XR0 34 
J 0
(-8529 4800);
DISPLAY 0.638298 (-8529 4800);
PAINT MONO (-8529 4800);
FORCEPROP 1 LAST COMMENT_BODY TRUE
J 2
(-8230 4705);
DISPLAY 0.872340 (-8230 4705);
PAINT PEACH (-8230 4705);
DISPLAY INVISIBLE (-8230 4705);
FORCEPROP 1 LAST OFFPAGE TRUE
J 2
(-8600 4675);
DISPLAY 0.872340 (-8600 4675);
PAINT GREEN (-8600 4675);
DISPLAY INVISIBLE (-8600 4675);
FORCEPROP 2 LAST CDS_LIB standard
J 0
(-8275 4800);
DISPLAY INVISIBLE (-8275 4800);
FORCEPROP 2 LAST PATH I23
J 0
(-8475 4850);
DISPLAY 0.680851 (-8475 4850);
DISPLAY INVISIBLE (-8475 4850);
FORCEADD OFFPAGE..1
(-8275 4750);
FORCEPROP 2 LAST $XR1 42 
J 0
(-8616 4750);
DISPLAY 0.638298 (-8616 4750);
PAINT MONO (-8616 4750);
FORCEPROP 2 LAST $XR0 15 
J 0
(-8526 4750);
DISPLAY 0.638298 (-8526 4750);
PAINT MONO (-8526 4750);
FORCEPROP 2 LAST CDS_LIB standard
J 0
(-8275 4750);
DISPLAY INVISIBLE (-8275 4750);
FORCEPROP 2 LAST PATH I24
J 0
(-8475 4800);
DISPLAY 0.680851 (-8475 4800);
DISPLAY INVISIBLE (-8475 4800);
FORCEPROP 1 LAST OFFPAGE TRUE
J 0
(-7950 4625);
DISPLAY 0.872340 (-7950 4625);
DISPLAY INVISIBLE (-7950 4625);
FORCEPROP 1 LAST COMMENT_BODY TRUE
J 0
(-8150 4650);
DISPLAY 0.872340 (-8150 4650);
PAINT GREEN (-8150 4650);
DISPLAY INVISIBLE (-8150 4650);
FORCEADD OFFPAGE..1
(-8275 4950);
FORCEPROP 2 LAST $XR1 11 
J 0
(-8616 4950);
DISPLAY 0.638298 (-8616 4950);
PAINT MONO (-8616 4950);
FORCEPROP 2 LAST $XR0 10 
J 0
(-8526 4950);
DISPLAY 0.638298 (-8526 4950);
PAINT MONO (-8526 4950);
FORCEPROP 2 LAST $XR2 12 
J 0
(-8706 4950);
DISPLAY 0.638298 (-8706 4950);
PAINT MONO (-8706 4950);
FORCEPROP 2 LAST $XR3 28 
J 0
(-8796 4950);
DISPLAY 0.638298 (-8796 4950);
PAINT MONO (-8796 4950);
FORCEPROP 2 LAST $XR4 46 
J 0
(-8886 4950);
DISPLAY 0.638298 (-8886 4950);
PAINT MONO (-8886 4950);
FORCEPROP 2 LAST PATH I25
J 0
(-8475 5000);
DISPLAY 0.680851 (-8475 5000);
DISPLAY INVISIBLE (-8475 5000);
FORCEPROP 1 LAST COMMENT_BODY TRUE
J 0
(-8150 4850);
DISPLAY 0.872340 (-8150 4850);
PAINT PEACH (-8150 4850);
DISPLAY INVISIBLE (-8150 4850);
FORCEPROP 1 LAST OFFPAGE TRUE
J 0
(-7950 4825);
DISPLAY 0.872340 (-7950 4825);
PAINT GREEN (-7950 4825);
DISPLAY INVISIBLE (-7950 4825);
FORCEPROP 2 LAST CDS_LIB standard
J 0
(-8275 4950);
DISPLAY INVISIBLE (-8275 4950);
FORCEADD OFFPAGE..1
(-8275 4900);
FORCEPROP 2 LAST $XR3 22 
J 0
(-8796 4900);
DISPLAY 0.638298 (-8796 4900);
PAINT MONO (-8796 4900);
FORCEPROP 2 LAST $XR0 10 
J 0
(-8526 4900);
DISPLAY 0.638298 (-8526 4900);
PAINT MONO (-8526 4900);
FORCEPROP 2 LAST $XR4 28 
J 0
(-8886 4900);
DISPLAY 0.638298 (-8886 4900);
PAINT MONO (-8886 4900);
FORCEPROP 2 LAST $XR1 11 
J 0
(-8616 4900);
DISPLAY 0.638298 (-8616 4900);
PAINT MONO (-8616 4900);
FORCEPROP 2 LAST $XR2 13 
J 0
(-8706 4900);
DISPLAY 0.638298 (-8706 4900);
PAINT MONO (-8706 4900);
FORCEPROP 2 LAST PATH I26
J 0
(-8475 4950);
DISPLAY 0.680851 (-8475 4950);
DISPLAY INVISIBLE (-8475 4950);
FORCEPROP 1 LAST COMMENT_BODY TRUE
J 0
(-8150 4800);
DISPLAY 0.872340 (-8150 4800);
PAINT PEACH (-8150 4800);
DISPLAY INVISIBLE (-8150 4800);
FORCEPROP 1 LAST OFFPAGE TRUE
J 0
(-7950 4775);
DISPLAY 0.872340 (-7950 4775);
PAINT GREEN (-7950 4775);
DISPLAY INVISIBLE (-7950 4775);
FORCEPROP 2 LAST CDS_LIB standard
J 0
(-8275 4900);
DISPLAY INVISIBLE (-8275 4900);
FORCEADD OFFPAGE..1
(-8275 5050);
FORCEPROP 2 LAST $XR0 13 
J 0
(-8526 5050);
DISPLAY 0.638298 (-8526 5050);
PAINT MONO (-8526 5050);
FORCEPROP 2 LAST PATH I27
J 0
(-8475 5100);
DISPLAY 0.680851 (-8475 5100);
DISPLAY INVISIBLE (-8475 5100);
FORCEPROP 2 LAST CDS_LIB standard
J 0
(-8275 5050);
DISPLAY 0.978723 (-8275 5050);
DISPLAY INVISIBLE (-8275 5050);
FORCEPROP 1 LAST OFFPAGE TRUE
J 0
(-7950 4925);
DISPLAY 0.851064 (-7950 4925);
PAINT GREEN (-7950 4925);
DISPLAY INVISIBLE (-7950 4925);
FORCEPROP 1 LAST COMMENT_BODY TRUE
J 0
(-8150 4950);
DISPLAY 0.851064 (-8150 4950);
PAINT PEACH (-8150 4950);
DISPLAY INVISIBLE (-8150 4950);
FORCEADD OFFPAGE..5
R 2
(-8075 5950);
FORCEPROP 2 LAST $XR1 13 
J 0
(-7796 5950);
DISPLAY 0.638298 (-7796 5950);
PAINT MONO (-7796 5950);
FORCEPROP 2 LAST $XR0 34 
J 0
(-7886 5950);
DISPLAY 0.638298 (-7886 5950);
PAINT MONO (-7886 5950);
FORCEPROP 1 LAST COMMENT_BODY TRUE
J 2
(-8175 5875);
DISPLAY 0.872340 (-8175 5875);
PAINT PEACH (-8175 5875);
DISPLAY INVISIBLE (-8175 5875);
FORCEPROP 1 LAST OFFPAGE TRUE
J 2
(-8400 5825);
DISPLAY 0.872340 (-8400 5825);
PAINT GREEN (-8400 5825);
DISPLAY INVISIBLE (-8400 5825);
FORCEPROP 2 LAST CDS_LIB standard
J 0
(-8075 5950);
DISPLAY INVISIBLE (-8075 5950);
FORCEPROP 2 LAST PATH I30
J 0
(-7775 6000);
DISPLAY 0.680851 (-7775 6000);
DISPLAY INVISIBLE (-7775 6000);
FORCEADD Q_RES..1
(-7050 3500);
FORCEPROP 1 LAST MATERIAL CHIP
J 0
(-6850 3500);
DISPLAY 0.510638 (-6850 3500);
PAINT SKYBLUE (-6850 3500);
FORCEPROP 1 LAST VALUE 0
J 2
(-6900 3500);
DISPLAY 0.510638 (-6900 3500);
PAINT SKYBLUE (-6900 3500);
FORCEPROP 1 LAST PATH I35
J 0
(-7100 3650);
DISPLAY 0.978723 (-7100 3650);
PAINT WHITE (-7100 3650);
DISPLAY INVISIBLE (-7100 3650);
FORCEPROP 1 LAST PART_NUMBER CS00002JB13
J 0
(-7150 3575);
DISPLAY 0.510638 (-7150 3575);
PAINT WHITE (-7150 3575);
DISPLAY INVISIBLE (-7150 3575);
FORCEPROP 2 LAST CDS_LIB pure_quanta
J 0
(-7050 3500);
DISPLAY INVISIBLE (-7050 3500);
FORCEPROP 1 LAST TOLERANCE 5%
J 0
(-7125 3600);
DISPLAY 0.510638 (-7125 3600);
PAINT SKYBLUE (-7125 3600);
DISPLAY INVISIBLE (-7125 3600);
FORCEPROP 1 LAST WATTAGE 1/16W
J 2
(-6700 3600);
DISPLAY 0.510638 (-6700 3600);
PAINT SKYBLUE (-6700 3600);
DISPLAY INVISIBLE (-6700 3600);
FORCEPROP 1 LAST PACK_TYPE 0402LF
J 0
(-7075 3550);
DISPLAY 0.510638 (-7075 3550);
PAINT SKYBLUE (-7075 3550);
DISPLAY INVISIBLE (-7075 3550);
FORCEPROP 1 LAST LOCATION R571
J 0
(-7250 3500);
DISPLAY 0.702128 (-7250 3500);
PAINT YELLOW (-7250 3500);
FORCEPROP 0 LAST $SEC 1
J 0
(-7200 3550);
DISPLAY 0.680851 (-7200 3550);
PAINT MONO (-7200 3550);
DISPLAY INVISIBLE (-7200 3550);
FORCEPROP 0 LAST CDS_SEC 1
J 0
(-7200 3550);
DISPLAY 1.021277 (-7200 3550);
DISPLAY INVISIBLE (-7200 3550);
FORCEPROP 1 LASTPIN (-7150 3500) $PN 1
J 0
(-7138 3512);
DISPLAY 0.808511 (-7138 3512);
PAINT WHITE (-7138 3512);
DISPLAY INVISIBLE (-7138 3512);
FORCEPROP 1 LASTPIN (-6950 3500) $PN 2
J 0
(-6988 3512);
DISPLAY 0.808511 (-6988 3512);
PAINT WHITE (-6988 3512);
DISPLAY INVISIBLE (-6988 3512);
FORCEADD Q_RES..1
(-7000 4750);
FORCEPROP 1 LAST VALUE 0
J 2
(-6850 4750);
DISPLAY 0.510638 (-6850 4750);
PAINT SKYBLUE (-6850 4750);
FORCEPROP 1 LAST MATERIAL CHIP
J 0
(-6800 4750);
DISPLAY 0.510638 (-6800 4750);
PAINT SKYBLUE (-6800 4750);
FORCEPROP 2 LAST CDS_LIB pure_quanta
J 0
(-7000 4750);
DISPLAY INVISIBLE (-7000 4750);
FORCEPROP 1 LAST PATH I37
J 0
(-7050 4900);
DISPLAY 0.978723 (-7050 4900);
PAINT WHITE (-7050 4900);
DISPLAY INVISIBLE (-7050 4900);
FORCEPROP 1 LAST PART_NUMBER CS00002JB13
J 0
(-7100 4825);
DISPLAY 0.510638 (-7100 4825);
PAINT WHITE (-7100 4825);
DISPLAY INVISIBLE (-7100 4825);
FORCEPROP 1 LAST TOLERANCE 5%
J 0
(-7075 4850);
DISPLAY 0.510638 (-7075 4850);
PAINT SKYBLUE (-7075 4850);
DISPLAY INVISIBLE (-7075 4850);
FORCEPROP 1 LAST WATTAGE 1/16W
J 2
(-6650 4850);
DISPLAY 0.510638 (-6650 4850);
PAINT SKYBLUE (-6650 4850);
DISPLAY INVISIBLE (-6650 4850);
FORCEPROP 1 LAST PACK_TYPE 0402LF
J 0
(-7025 4800);
DISPLAY 0.510638 (-7025 4800);
PAINT SKYBLUE (-7025 4800);
DISPLAY INVISIBLE (-7025 4800);
FORCEPROP 1 LAST LOCATION R634
J 0
(-7225 4750);
DISPLAY 0.702128 (-7225 4750);
PAINT YELLOW (-7225 4750);
FORCEPROP 0 LAST $SEC 1
J 0
(-7150 4800);
DISPLAY 0.680851 (-7150 4800);
PAINT MONO (-7150 4800);
DISPLAY INVISIBLE (-7150 4800);
FORCEPROP 0 LAST CDS_SEC 1
J 0
(-7150 4800);
DISPLAY 1.021277 (-7150 4800);
DISPLAY INVISIBLE (-7150 4800);
FORCEPROP 1 LASTPIN (-7100 4750) $PN 1
J 0
(-7088 4762);
DISPLAY 0.808511 (-7088 4762);
PAINT WHITE (-7088 4762);
DISPLAY INVISIBLE (-7088 4762);
FORCEPROP 1 LASTPIN (-6900 4750) $PN 2
J 0
(-6938 4762);
DISPLAY 0.808511 (-6938 4762);
PAINT WHITE (-6938 4762);
DISPLAY INVISIBLE (-6938 4762);
FORCEADD OFFPAGE..4
R 2
(-6725 3650);
FORCEPROP 2 LAST $XR0 32 
J 0
(-6946 3650);
DISPLAY 0.638298 (-6946 3650);
PAINT MONO (-6946 3650);
FORCEPROP 2 LAST PATH I42
J 0
(-6925 3700);
DISPLAY 0.680851 (-6925 3700);
DISPLAY INVISIBLE (-6925 3700);
FORCEPROP 2 LAST CDS_LIB standard
J 2
(-6725 3650);
DISPLAY INVISIBLE (-6725 3650);
FORCEPROP 1 LAST OFFPAGE TRUE
J 2
(-7050 3525);
DISPLAY 0.872340 (-7050 3525);
PAINT GREEN (-7050 3525);
DISPLAY INVISIBLE (-7050 3525);
FORCEPROP 1 LAST COMMENT_BODY TRUE
J 2
(-6700 3550);
DISPLAY 0.872340 (-6700 3550);
PAINT PEACH (-6700 3550);
DISPLAY INVISIBLE (-6700 3550);
FORCEADD OFFPAGE..4
R 2
(-6725 3700);
FORCEPROP 2 LAST $XR0 32 
J 0
(-6946 3700);
DISPLAY 0.638298 (-6946 3700);
PAINT MONO (-6946 3700);
FORCEPROP 1 LAST COMMENT_BODY TRUE
J 2
(-6700 3600);
DISPLAY 0.872340 (-6700 3600);
PAINT PEACH (-6700 3600);
DISPLAY INVISIBLE (-6700 3600);
FORCEPROP 1 LAST OFFPAGE TRUE
J 2
(-7050 3575);
DISPLAY 0.872340 (-7050 3575);
PAINT GREEN (-7050 3575);
DISPLAY INVISIBLE (-7050 3575);
FORCEPROP 2 LAST CDS_LIB standard
J 2
(-6725 3700);
DISPLAY INVISIBLE (-6725 3700);
FORCEPROP 2 LAST PATH I43
J 0
(-6925 3750);
DISPLAY 0.680851 (-6925 3750);
DISPLAY INVISIBLE (-6925 3750);
FORCEADD OFFPAGE..4
R 2
(-6725 4250);
FORCEPROP 2 LAST $XR0 32 
J 0
(-6976 4250);
DISPLAY 0.638298 (-6976 4250);
PAINT MONO (-6976 4250);
FORCEPROP 1 LAST COMMENT_BODY TRUE
J 2
(-6700 4150);
DISPLAY 0.872340 (-6700 4150);
PAINT PEACH (-6700 4150);
DISPLAY INVISIBLE (-6700 4150);
FORCEPROP 1 LAST OFFPAGE TRUE
J 2
(-7050 4125);
DISPLAY 0.872340 (-7050 4125);
PAINT GREEN (-7050 4125);
DISPLAY INVISIBLE (-7050 4125);
FORCEPROP 2 LAST CDS_LIB standard
J 2
(-6725 4250);
DISPLAY INVISIBLE (-6725 4250);
FORCEPROP 2 LAST PATH I44
J 0
(-6975 4300);
DISPLAY 0.680851 (-6975 4300);
DISPLAY INVISIBLE (-6975 4300);
FORCEADD OFFPAGE..2
R 2
(-6725 4300);
FORCEPROP 2 LAST $XR0 32 
J 0
(-6949 4300);
DISPLAY 0.638298 (-6949 4300);
PAINT MONO (-6949 4300);
FORCEPROP 1 LAST COMMENT_BODY TRUE
J 2
(-6680 4205);
DISPLAY 0.872340 (-6680 4205);
PAINT PEACH (-6680 4205);
DISPLAY INVISIBLE (-6680 4205);
FORCEPROP 1 LAST OFFPAGE TRUE
J 2
(-7050 4175);
DISPLAY 0.872340 (-7050 4175);
PAINT GREEN (-7050 4175);
DISPLAY INVISIBLE (-7050 4175);
FORCEPROP 2 LAST CDS_LIB standard
J 2
(-6725 4300);
DISPLAY INVISIBLE (-6725 4300);
FORCEPROP 2 LAST PATH I45
J 0
(-6975 4350);
DISPLAY 0.680851 (-6975 4350);
DISPLAY INVISIBLE (-6975 4350);
FORCEADD OFFPAGE..2
(-1075 3550);
FORCEPROP 2 LAST $XR0 12 
J 0
(-886 3550);
DISPLAY 0.638298 (-886 3550);
PAINT MONO (-886 3550);
FORCEPROP 2 LAST PATH I77
J 0
(-875 3600);
DISPLAY 0.680851 (-875 3600);
DISPLAY INVISIBLE (-875 3600);
FORCEPROP 2 LAST CDS_LIB standard
J 0
(-1075 3550);
DISPLAY INVISIBLE (-1075 3550);
FORCEPROP 1 LAST OFFPAGE TRUE
J 0
(-750 3425);
DISPLAY 0.872340 (-750 3425);
PAINT GREEN (-750 3425);
DISPLAY INVISIBLE (-750 3425);
FORCEPROP 1 LAST COMMENT_BODY TRUE
J 0
(-1120 3455);
DISPLAY 0.872340 (-1120 3455);
PAINT PEACH (-1120 3455);
DISPLAY INVISIBLE (-1120 3455);
FORCEADD OFFPAGE..4
(-1075 3600);
FORCEPROP 2 LAST $XR1 11 
J 0
(-799 3600);
DISPLAY 0.638298 (-799 3600);
PAINT MONO (-799 3600);
FORCEPROP 2 LAST $XR0 10 
J 0
(-889 3600);
DISPLAY 0.638298 (-889 3600);
PAINT MONO (-889 3600);
FORCEPROP 2 LAST PATH I78
J 0
(-775 3650);
DISPLAY 0.680851 (-775 3650);
DISPLAY INVISIBLE (-775 3650);
FORCEPROP 2 LAST CDS_LIB standard
J 0
(-1075 3600);
DISPLAY INVISIBLE (-1075 3600);
FORCEPROP 1 LAST OFFPAGE TRUE
J 0
(-750 3475);
DISPLAY 0.872340 (-750 3475);
PAINT GREEN (-750 3475);
DISPLAY INVISIBLE (-750 3475);
FORCEPROP 1 LAST COMMENT_BODY TRUE
J 0
(-1100 3500);
DISPLAY 0.872340 (-1100 3500);
PAINT PEACH (-1100 3500);
DISPLAY INVISIBLE (-1100 3500);
FORCEADD OFFPAGE..2
(-1075 3700);
FORCEPROP 2 LAST $XR1 10 
J 0
(-796 3700);
DISPLAY 0.638298 (-796 3700);
PAINT MONO (-796 3700);
FORCEPROP 2 LAST $XR0 11 
J 0
(-886 3700);
DISPLAY 0.638298 (-886 3700);
PAINT MONO (-886 3700);
FORCEPROP 2 LAST PATH I79
J 0
(-775 3750);
DISPLAY 0.680851 (-775 3750);
DISPLAY INVISIBLE (-775 3750);
FORCEPROP 2 LAST CDS_LIB standard
J 0
(-1075 3700);
DISPLAY INVISIBLE (-1075 3700);
FORCEPROP 1 LAST OFFPAGE TRUE
J 0
(-750 3575);
DISPLAY 0.872340 (-750 3575);
PAINT GREEN (-750 3575);
DISPLAY INVISIBLE (-750 3575);
FORCEPROP 1 LAST COMMENT_BODY TRUE
J 0
(-1120 3605);
DISPLAY 0.872340 (-1120 3605);
PAINT PEACH (-1120 3605);
DISPLAY INVISIBLE (-1120 3605);
FORCEADD OFFPAGE..5
(-8250 3350);
FORCEPROP 2 LAST $XR0 13 
J 0
(-8474 3350);
DISPLAY 0.638298 (-8474 3350);
PAINT MONO (-8474 3350);
FORCEPROP 1 LAST COMMENT_BODY TRUE
J 0
(-8150 3275);
DISPLAY 0.872340 (-8150 3275);
PAINT PEACH (-8150 3275);
DISPLAY INVISIBLE (-8150 3275);
FORCEPROP 1 LAST OFFPAGE TRUE
J 0
(-7925 3225);
DISPLAY 0.872340 (-7925 3225);
PAINT GREEN (-7925 3225);
DISPLAY INVISIBLE (-7925 3225);
FORCEPROP 2 LAST CDS_LIB standard
J 0
(-8250 3350);
DISPLAY INVISIBLE (-8250 3350);
FORCEPROP 2 LAST PATH I8
J 0
(-8450 3400);
DISPLAY 0.680851 (-8450 3400);
DISPLAY INVISIBLE (-8450 3400);
FORCEADD OFFPAGE..2
(-1075 3750);
FORCEPROP 2 LAST $XR1 10 
J 0
(-796 3750);
DISPLAY 0.638298 (-796 3750);
PAINT MONO (-796 3750);
FORCEPROP 2 LAST $XR0 11 
J 0
(-886 3750);
DISPLAY 0.638298 (-886 3750);
PAINT MONO (-886 3750);
FORCEPROP 2 LAST PATH I80
J 0
(-775 3800);
DISPLAY 0.680851 (-775 3800);
DISPLAY INVISIBLE (-775 3800);
FORCEPROP 2 LAST CDS_LIB standard
J 0
(-1075 3750);
DISPLAY INVISIBLE (-1075 3750);
FORCEPROP 1 LAST OFFPAGE TRUE
J 0
(-750 3625);
DISPLAY 0.872340 (-750 3625);
PAINT GREEN (-750 3625);
DISPLAY INVISIBLE (-750 3625);
FORCEPROP 1 LAST COMMENT_BODY TRUE
J 0
(-1120 3655);
DISPLAY 0.872340 (-1120 3655);
PAINT PEACH (-1120 3655);
DISPLAY INVISIBLE (-1120 3655);
FORCEADD OFFPAGE..2
(-1075 3850);
FORCEPROP 2 LAST $XR1 10 
J 0
(-796 3850);
DISPLAY 0.638298 (-796 3850);
PAINT MONO (-796 3850);
FORCEPROP 2 LAST $XR0 11 
J 0
(-886 3850);
DISPLAY 0.638298 (-886 3850);
PAINT MONO (-886 3850);
FORCEPROP 2 LAST PATH I81
J 0
(-775 3900);
DISPLAY 0.680851 (-775 3900);
DISPLAY INVISIBLE (-775 3900);
FORCEPROP 2 LAST CDS_LIB standard
J 0
(-1075 3850);
DISPLAY INVISIBLE (-1075 3850);
FORCEPROP 1 LAST OFFPAGE TRUE
J 0
(-750 3725);
DISPLAY 0.872340 (-750 3725);
PAINT GREEN (-750 3725);
DISPLAY INVISIBLE (-750 3725);
FORCEPROP 1 LAST COMMENT_BODY TRUE
J 0
(-1120 3755);
DISPLAY 0.872340 (-1120 3755);
PAINT PEACH (-1120 3755);
DISPLAY INVISIBLE (-1120 3755);
FORCEADD OFFPAGE..4
(-1075 3900);
FORCEPROP 2 LAST $XR0 15 
J 0
(-889 3900);
DISPLAY 0.638298 (-889 3900);
PAINT MONO (-889 3900);
FORCEPROP 2 LAST PATH I82
J 0
(-875 3950);
DISPLAY 0.680851 (-875 3950);
DISPLAY INVISIBLE (-875 3950);
FORCEPROP 2 LAST CDS_LIB standard
J 0
(-1075 3900);
DISPLAY INVISIBLE (-1075 3900);
FORCEPROP 1 LAST OFFPAGE TRUE
J 0
(-750 3775);
DISPLAY 0.872340 (-750 3775);
PAINT GREEN (-750 3775);
DISPLAY INVISIBLE (-750 3775);
FORCEPROP 1 LAST COMMENT_BODY TRUE
J 0
(-1100 3800);
DISPLAY 0.872340 (-1100 3800);
PAINT PEACH (-1100 3800);
DISPLAY INVISIBLE (-1100 3800);
FORCEADD OFFPAGE..2
(-1075 4000);
FORCEPROP 2 LAST $XR0 15 
J 0
(-886 4000);
DISPLAY 0.638298 (-886 4000);
PAINT MONO (-886 4000);
FORCEPROP 2 LAST PATH I83
J 0
(-875 4050);
DISPLAY 0.680851 (-875 4050);
DISPLAY INVISIBLE (-875 4050);
FORCEPROP 2 LAST CDS_LIB standard
J 0
(-1075 4000);
DISPLAY INVISIBLE (-1075 4000);
FORCEPROP 1 LAST OFFPAGE TRUE
J 0
(-750 3875);
DISPLAY 0.872340 (-750 3875);
PAINT GREEN (-750 3875);
DISPLAY INVISIBLE (-750 3875);
FORCEPROP 1 LAST COMMENT_BODY TRUE
J 0
(-1120 3905);
DISPLAY 0.872340 (-1120 3905);
PAINT PEACH (-1120 3905);
DISPLAY INVISIBLE (-1120 3905);
FORCEADD OFFPAGE..2
(-1075 4050);
FORCEPROP 2 LAST $XR0 15 
J 0
(-886 4050);
DISPLAY 0.638298 (-886 4050);
PAINT MONO (-886 4050);
FORCEPROP 2 LAST PATH I84
J 0
(-875 4100);
DISPLAY 0.680851 (-875 4100);
DISPLAY INVISIBLE (-875 4100);
FORCEPROP 2 LAST CDS_LIB standard
J 0
(-1075 4050);
DISPLAY INVISIBLE (-1075 4050);
FORCEPROP 1 LAST OFFPAGE TRUE
J 0
(-750 3925);
DISPLAY 0.872340 (-750 3925);
PAINT GREEN (-750 3925);
DISPLAY INVISIBLE (-750 3925);
FORCEPROP 1 LAST COMMENT_BODY TRUE
J 0
(-1120 3955);
DISPLAY 0.872340 (-1120 3955);
PAINT PEACH (-1120 3955);
DISPLAY INVISIBLE (-1120 3955);
FORCEADD OFFPAGE..2
(-1075 4150);
FORCEPROP 2 LAST $XR0 15 
J 0
(-886 4150);
DISPLAY 0.638298 (-886 4150);
PAINT MONO (-886 4150);
FORCEPROP 2 LAST PATH I85
J 0
(-875 4200);
DISPLAY 0.680851 (-875 4200);
DISPLAY INVISIBLE (-875 4200);
FORCEPROP 2 LAST CDS_LIB standard
J 0
(-1075 4150);
DISPLAY INVISIBLE (-1075 4150);
FORCEPROP 1 LAST OFFPAGE TRUE
J 0
(-750 4025);
DISPLAY 0.872340 (-750 4025);
PAINT GREEN (-750 4025);
DISPLAY INVISIBLE (-750 4025);
FORCEPROP 1 LAST COMMENT_BODY TRUE
J 0
(-1120 4055);
DISPLAY 0.872340 (-1120 4055);
PAINT PEACH (-1120 4055);
DISPLAY INVISIBLE (-1120 4055);
FORCEADD OFFPAGE..2
(-1075 4200);
FORCEPROP 2 LAST $XR0 15 
J 0
(-886 4200);
DISPLAY 0.638298 (-886 4200);
PAINT MONO (-886 4200);
FORCEPROP 2 LAST PATH I86
J 0
(-875 4250);
DISPLAY 0.680851 (-875 4250);
DISPLAY INVISIBLE (-875 4250);
FORCEPROP 2 LAST CDS_LIB standard
J 0
(-1075 4200);
DISPLAY INVISIBLE (-1075 4200);
FORCEPROP 1 LAST OFFPAGE TRUE
J 0
(-750 4075);
DISPLAY 0.872340 (-750 4075);
PAINT GREEN (-750 4075);
DISPLAY INVISIBLE (-750 4075);
FORCEPROP 1 LAST COMMENT_BODY TRUE
J 0
(-1120 4105);
DISPLAY 0.872340 (-1120 4105);
PAINT PEACH (-1120 4105);
DISPLAY INVISIBLE (-1120 4105);
FORCEADD OFFPAGE..2
(-1075 4300);
FORCEPROP 2 LAST $XR0 15 
J 0
(-886 4300);
DISPLAY 0.638298 (-886 4300);
PAINT MONO (-886 4300);
FORCEPROP 2 LAST PATH I87
J 0
(-875 4350);
DISPLAY 0.680851 (-875 4350);
DISPLAY INVISIBLE (-875 4350);
FORCEPROP 2 LAST CDS_LIB standard
J 0
(-1075 4300);
DISPLAY INVISIBLE (-1075 4300);
FORCEPROP 1 LAST OFFPAGE TRUE
J 0
(-750 4175);
DISPLAY 0.872340 (-750 4175);
PAINT GREEN (-750 4175);
DISPLAY INVISIBLE (-750 4175);
FORCEPROP 1 LAST COMMENT_BODY TRUE
J 0
(-1120 4205);
DISPLAY 0.872340 (-1120 4205);
PAINT PEACH (-1120 4205);
DISPLAY INVISIBLE (-1120 4205);
FORCEADD OFFPAGE..2
(-1075 4350);
FORCEPROP 2 LAST $XR1 22 
J 0
(-796 4350);
DISPLAY 0.638298 (-796 4350);
PAINT MONO (-796 4350);
FORCEPROP 2 LAST $XR0 15 
J 0
(-886 4350);
DISPLAY 0.638298 (-886 4350);
PAINT MONO (-886 4350);
FORCEPROP 2 LAST PATH I88
J 0
(-775 4400);
DISPLAY 0.680851 (-775 4400);
DISPLAY INVISIBLE (-775 4400);
FORCEPROP 2 LAST CDS_LIB standard
J 2
(-1075 4350);
DISPLAY INVISIBLE (-1075 4350);
FORCEPROP 1 LAST OFFPAGE TRUE
J 0
(-750 4225);
DISPLAY 0.872340 (-750 4225);
PAINT GREEN (-750 4225);
DISPLAY INVISIBLE (-750 4225);
FORCEPROP 1 LAST COMMENT_BODY TRUE
J 0
(-1120 4255);
DISPLAY 0.872340 (-1120 4255);
PAINT PEACH (-1120 4255);
DISPLAY INVISIBLE (-1120 4255);
FORCEADD OFFPAGE..5
R 2
(-1075 4600);
FORCEPROP 2 LAST $XR2 28 
J 0
(-706 4600);
DISPLAY 0.638298 (-706 4600);
PAINT MONO (-706 4600);
FORCEPROP 2 LAST $XR1 13 
J 0
(-796 4600);
DISPLAY 0.638298 (-796 4600);
PAINT MONO (-796 4600);
FORCEPROP 2 LAST $XR0 11 
J 0
(-886 4600);
DISPLAY 0.638298 (-886 4600);
PAINT MONO (-886 4600);
FORCEPROP 1 LAST COMMENT_BODY TRUE
J 2
(-1175 4525);
DISPLAY 0.872340 (-1175 4525);
PAINT PEACH (-1175 4525);
DISPLAY INVISIBLE (-1175 4525);
FORCEPROP 1 LAST OFFPAGE TRUE
J 2
(-1400 4475);
DISPLAY 0.872340 (-1400 4475);
PAINT GREEN (-1400 4475);
DISPLAY INVISIBLE (-1400 4475);
FORCEPROP 2 LAST CDS_LIB standard
J 2
(-1075 4600);
DISPLAY INVISIBLE (-1075 4600);
FORCEPROP 2 LAST PATH I89
J 0
(-700 4650);
DISPLAY 0.680851 (-700 4650);
DISPLAY INVISIBLE (-700 4650);
FORCEADD OFFPAGE..5
(-8250 3400);
FORCEPROP 2 LAST $XR1 13 
J 0
(-8564 3400);
DISPLAY 0.638298 (-8564 3400);
PAINT MONO (-8564 3400);
FORCEPROP 2 LAST $XR0 12 
J 0
(-8474 3400);
DISPLAY 0.638298 (-8474 3400);
PAINT MONO (-8474 3400);
FORCEPROP 1 LAST COMMENT_BODY TRUE
J 0
(-8150 3325);
DISPLAY 0.872340 (-8150 3325);
PAINT PEACH (-8150 3325);
DISPLAY INVISIBLE (-8150 3325);
FORCEPROP 1 LAST OFFPAGE TRUE
J 0
(-7925 3275);
DISPLAY 0.872340 (-7925 3275);
PAINT GREEN (-7925 3275);
DISPLAY INVISIBLE (-7925 3275);
FORCEPROP 2 LAST CDS_LIB standard
J 0
(-8250 3400);
DISPLAY INVISIBLE (-8250 3400);
FORCEPROP 2 LAST PATH I9
J 0
(-8450 3450);
DISPLAY 0.680851 (-8450 3450);
DISPLAY INVISIBLE (-8450 3450);
FORCEADD OFFPAGE..4
(-1075 4950);
FORCEPROP 2 LAST $XR0 13 
J 0
(-889 4950);
DISPLAY 0.638298 (-889 4950);
PAINT MONO (-889 4950);
FORCEPROP 2 LAST PATH I93
J 0
(-875 5000);
DISPLAY 0.680851 (-875 5000);
DISPLAY INVISIBLE (-875 5000);
FORCEPROP 2 LAST CDS_LIB standard
J 0
(-1075 4950);
DISPLAY INVISIBLE (-1075 4950);
FORCEPROP 1 LAST OFFPAGE TRUE
J 0
(-750 4825);
DISPLAY 0.872340 (-750 4825);
DISPLAY INVISIBLE (-750 4825);
FORCEPROP 1 LAST COMMENT_BODY TRUE
J 0
(-1100 4850);
DISPLAY 0.872340 (-1100 4850);
PAINT GREEN (-1100 4850);
DISPLAY INVISIBLE (-1100 4850);
FORCEADD OFFPAGE..5
R 2
(-1075 5250);
FORCEPROP 2 LAST $XR0 22 
J 0
(-886 5250);
DISPLAY 0.638298 (-886 5250);
PAINT MONO (-886 5250);
FORCEPROP 2 LAST PATH I96
J 0
(-875 5300);
DISPLAY 0.680851 (-875 5300);
DISPLAY INVISIBLE (-875 5300);
FORCEPROP 2 LAST CDS_LIB standard
J 2
(-1075 5250);
DISPLAY INVISIBLE (-1075 5250);
FORCEPROP 1 LAST OFFPAGE TRUE
J 2
(-1400 5125);
DISPLAY 0.872340 (-1400 5125);
PAINT GREEN (-1400 5125);
DISPLAY INVISIBLE (-1400 5125);
FORCEPROP 1 LAST COMMENT_BODY TRUE
J 2
(-1175 5175);
DISPLAY 0.872340 (-1175 5175);
PAINT PEACH (-1175 5175);
DISPLAY INVISIBLE (-1175 5175);
FORCEADD QUANTA_TITLE_BLOCK_C..1
(0 0);
FORCEPROP 0 LAST CDS_CON_LAST_MODIFIED Fri Aug 25 17:25:43 2023
J 0
(-1885 15);
DISPLAY INVISIBLE (-1885 15);
FORCEPROP 2 LAST Q_DEPT 
J 1
(-3763 49);
DISPLAY 1.957447 (-3763 49);
PAINT GREEN (-3763 49);
FORCEPROP 1 LAST CUSTOM_TXT_CDS <CON_LAST_MODIFIED>
J 0
(-1885 15);
DISPLAY 0.978723 (-1885 15);
FORCEPROP 2 LAST CUSTOM_TXT_CDS <XR_PAGE_TITLE>
J 0
(-7890 5250);
DISPLAY 0.638298 (-7890 5250);
PAINT PINK (-7890 5250);
DISPLAY INVISIBLE (-7890 5250);
FORCEPROP 1 LAST CUSTOM_TXT_CDS <NAME_2>
J 0
(-3175 50);
FORCEPROP 1 LAST CUSTOM_TXT_CDS <NAME_1>
J 0
(-3175 175);
FORCEPROP 1 LAST CUSTOM_TXT_CDS <Q_NUMBER>
J 0
(-1403 103);
DISPLAY 1.212766 (-1403 103);
FORCEPROP 1 LAST CUSTOM_TXT_CDS <Q_PROJ>
J 0
(-2382 102);
DISPLAY 1.212766 (-2382 102);
FORCEPROP 1 LAST CUSTOM_TXT_CDS <Q_REV>
J 0
(-184 103);
DISPLAY 1.212766 (-184 103);
FORCEPROP 1 LAST CUSTOM_TXT_CDS <CON_PAGE_NUM> OF <CON_TOTAL_PAGES>
J 0
(-446 18);
DISPLAY 0.978723 (-446 18);
FORCEPROP 1 LAST Q_TITLE FPGA 1/8
J 0
(-9366 26);
DISPLAY 2.446809 (-9366 26);
PAINT GREEN (-9366 26);
FORCEPROP 2 LAST PAGE_BORDER TRUE
J 0
(-7890 5250);
DISPLAY 0.638298 (-7890 5250);
PAINT PINK (-7890 5250);
DISPLAY INVISIBLE (-7890 5250);
FORCEPROP 1 LAST CDS_LMAN_SYM_OUTLINE -9475,6775,100,-125
J 0
(0 0);
DISPLAY 0.468085 (0 0);
PAINT GREEN (0 0);
DISPLAY INVISIBLE (0 0);
FORCEPROP 1 LAST COMMENT_BODY TRUE
J 0
(12 -13);
DISPLAY 0.978723 (12 -13);
PAINT GREEN (12 -13);
DISPLAY INVISIBLE (12 -13);
FORCEPROP 2 LAST CDS_LIB pure_quanta
J 0
(0 0);
DISPLAY INVISIBLE (0 0);
FORCEPROP 2 LAST CDS_XR_PAGE_TITLE CR-34 : @SCM_LIB.SCM(SCH_1):PAGE34
J 0
(-7890 5250);
DISPLAY 0.638298 (-7890 5250);
PAINT PINK (-7890 5250);
DISPLAY INVISIBLE (-7890 5250);
WIRE 16 -1 (-3975 1425)(-3975 1325);
WIRE 16 -1 (-6350 1900)(-6350 1850);
WIRE 16 -1 (-4375 1050)(-4375 1225);
WIRE 16 -1 (-6400 875)(-6400 750);
WIRE 16 -1 (-6000 3100)(-6000 3050);
WIRE 16 -1 (-8400 2100)(-8400 1850);
WIRE 16 -1 (-600 4475)(-600 4450);
WIRE 16 -1 (-3800 3150)(-3800 3100);
WIRE 16 -1 (-8750 6300)(-8750 6250);
WIRE 16 -1 (-6725 1250)(-6725 1375);
WIRE 16 -1 (-2725 700)(-2725 550);
WIRE 16 -1 (-2900 700)(-2725 700);
WIRE 16 -1 (-3975 1025)(-3975 875);
WIRE 16 -1 (-3975 3100)(-4175 3100);
WIRE 16 -1 (-3800 3100)(-3975 3100);
WIRE 16 -1 (-3975 3050)(-3975 3100);
WIRE 16 -1 (-4175 3050)(-3975 3050);
WIRE 16 -1 (-6000 3050)(-5825 3050);
WIRE 16 -1 (-5825 3050)(-5625 3050);
WIRE 16 -1 (-5825 3000)(-5825 3050);
WIRE 16 -1 (-5825 3000)(-5625 3000);
WIRE 16 3135 (-4600 1650)(-400 1650);
WIRE 16 3135 (-400 1650)(-400 450);
WIRE 16 3135 (-4600 450)(-4600 1650);
WIRE 16 3135 (-4600 450)(-400 450);
WIRE 16 -1 (-6850 750)(-6400 750);
WIRE 16 -1 (-6400 700)(-6400 750);
WIRE 16 -1 (-6850 700)(-6400 700);
WIRE 16 -1 (-6400 650)(-6400 700);
WIRE 16 -1 (-6850 650)(-6400 650);
WIRE 16 -1 (-3975 1225)(-3975 1325);
WIRE 16 -1 (-3725 1325)(-3975 1325);
WIRE 16 -1 (-3725 850)(-3725 1325);
WIRE 16 -1 (-3550 850)(-3725 850);
WIRE 16 -1 (-2450 4450)(-600 4450);
WIRE 16 -1 (-8300 1850)(-8400 1850);
WIRE 16 -1 (-6725 1375)(-6725 1525);
WIRE 16 -1 (-6725 1375)(-7375 1375);
WIRE 16 -1 (-7375 1550)(-7375 1375);
WIRE 16 -1 (-6725 1725)(-6725 1850);
WIRE 16 -1 (-6350 1850)(-6725 1850);
WIRE 16 -1 (-7375 1750)(-7375 1850);
WIRE 16 -1 (-6725 1850)(-7375 1850);
WIRE 16 -1 (-8100 1850)(-7375 1850);
WIRE 16 -1 (-2900 850)(-1900 850);
FORCEPROP 2 LAST SIG_NAME CLK_25M_OSC_FPGA_R
J 0
(-2810 860);
DISPLAY 0.808511 (-2810 860);
WIRE 16 -1 (-4175 4050)(-1125 4050);
FORCEPROP 2 LAST SIG_NAME IRQ_OC_DETECT_N
J 2
(-1100 4060);
DISPLAY 0.808511 (-1100 4060);
WIRE 16 -1 (-1125 4150)(-4175 4150);
FORCEPROP 2 LAST SIG_NAME IRQ_CPU1_VRHOT_N
J 2
(-1100 4160);
DISPLAY 0.808511 (-1100 4160);
WIRE 16 -1 (-1125 4200)(-4175 4200);
FORCEPROP 2 LAST SIG_NAME IRQ_CPU0_VRHOT_N
J 2
(-1100 4210);
DISPLAY 0.808511 (-1100 4210);
WIRE 16 -1 (-1125 4300)(-4175 4300);
FORCEPROP 2 LAST SIG_NAME PWRGD_CPUPWRGD_LVC1
J 2
(-1100 4310);
DISPLAY 0.808511 (-1100 4310);
WIRE 16 -1 (-4175 4350)(-2650 4350);
FORCEPROP 2 LAST SIG_NAME RST_EXTRST_R_N
J 0
(-3985 4360);
DISPLAY 0.808511 (-3985 4360);
WIRE 16 -1 (-4175 4750)(-2650 4750);
FORCEPROP 2 LAST SIG_NAME TP_PLD_19D
J 2
(-3610 4760);
DISPLAY 0.808511 (-3610 4760);
WIRE 16 -1 (-4175 4950)(-1125 4950);
FORCEPROP 0 LAST SIG_NAME IRQ_PCH_SCI_WHEA_N
J 2
(-1210 4960);
DISPLAY 0.808511 (-1210 4960);
WIRE 16 -1 (-1125 5050)(-2625 5050);
FORCEPROP 2 LAST SIG_NAME SMB_BMC_MM16_R5_SDA
J 0
(-1910 5060);
DISPLAY 0.851064 (-1910 5060);
WIRE 16 -1 (-1125 5100)(-2625 5100);
FORCEPROP 2 LAST SIG_NAME SMB_BMC_MM16_R5_SCL
J 0
(-1910 5110);
DISPLAY 0.851064 (-1910 5110);
WIRE 16 -1 (-2650 4600)(-4175 4600);
FORCEPROP 2 LAST SIG_NAME FM_CPU_MSMI_CATERR_LVT3_PLD_N
J 0
(-3985 4610);
DISPLAY 0.808511 (-3985 4610);
WIRE 16 -1 (-5625 4750)(-6900 4750);
FORCEPROP 2 LAST SIG_NAME FM_JTAG_BMC_MUX_SEL_R2
J 0
(-6610 4760);
DISPLAY 0.851064 (-6610 4760);
WIRE 16 -1 (-8225 4800)(-5625 4800);
FORCEPROP 2 LAST SIG_NAME RST_RSMRST_N
J 0
(-8175 4810);
DISPLAY 0.808511 (-8175 4810);
WIRE 16 -1 (-8225 4600)(-5625 4600);
FORCEPROP 2 LAST SIG_NAME RST_PCA9548_SENSOR_N
J 0
(-8185 4610);
DISPLAY 0.851064 (-8185 4610);
WIRE 16 -1 (-6900 4650)(-5625 4650);
FORCEPROP 2 LAST SIG_NAME BSM_PRSNT_R1_N
J 0
(-6610 4660);
DISPLAY 0.808511 (-6610 4660);
WIRE 16 -1 (-8225 5050)(-5625 5050);
FORCEPROP 2 LAST SIG_NAME IRQ_BMC_CPU_NMI_R
J 0
(-8210 5060);
DISPLAY 0.808511 (-8210 5060);
WIRE 16 -1 (-5625 4900)(-6900 4900);
FORCEPROP 2 LAST SIG_NAME PWRGD_PSU_AC_PWROK_PLD
J 0
(-6610 4910);
DISPLAY 0.808511 (-6610 4910);
WIRE 16 -1 (-6900 4950)(-5625 4950);
FORCEPROP 2 LAST SIG_NAME RST_PLTRST_R1_N
J 0
(-6610 4960);
DISPLAY 0.808511 (-6610 4960);
WIRE 16 -1 (-8225 4150)(-5625 4150);
FORCEPROP 2 LAST SIG_NAME IRQ_UV_DETECT_N
J 0
(-8210 4160);
DISPLAY 0.808511 (-8210 4160);
WIRE 16 -1 (-8225 4100)(-5625 4100);
FORCEPROP 2 LAST SIG_NAME RST_BMC_RSTBTN_OUT_N
J 0
(-8210 4110);
DISPLAY 0.808511 (-8210 4110);
WIRE 16 -1 (-5625 4000)(-7025 4000);
FORCEPROP 2 LAST SIG_NAME BMC_CPLD_GPIO_2_R2
J 0
(-6610 4010);
DISPLAY 0.851064 (-6610 4010);
WIRE 16 -1 (-8225 3950)(-5625 3950);
FORCEPROP 2 LAST SIG_NAME FM_ME_BT_DONE
J 0
(-8225 3960);
DISPLAY 0.808511 (-8225 3960);
WIRE 16 -1 (-5625 3550)(-8225 3550);
FORCEPROP 2 LAST SIG_NAME CLK_25M_OSC_FPGA
J 0
(-8200 3560);
DISPLAY 0.808511 (-8200 3560);
WIRE 16 -1 (-5625 3500)(-6950 3500);
FORCEPROP 2 LAST SIG_NAME IRQ_BMC_PCH_NMI_R_N
J 0
(-6635 3510);
DISPLAY 0.808511 (-6635 3510);
WIRE 16 -1 (-5625 3650)(-6675 3650);
FORCEPROP 2 LAST SIG_NAME JTAG_SCM_PLD_TMS
J 0
(-6625 3660);
DISPLAY 0.808511 (-6625 3660);
WIRE 16 -1 (-5625 3700)(-6675 3700);
FORCEPROP 2 LAST SIG_NAME JTAG_SCM_PLD_TCK
J 0
(-6625 3710);
DISPLAY 0.808511 (-6625 3710);
WIRE 16 -1 (-8200 3400)(-5625 3400);
FORCEPROP 2 LAST SIG_NAME FM_PCH_BMC_THERMTRIP_N
J 0
(-8185 3410);
DISPLAY 0.808511 (-8185 3410);
WIRE 16 -1 (-5625 3350)(-8200 3350);
FORCEPROP 2 LAST SIG_NAME H_CPU1_PROCHOT_LVC1_R_N
J 0
(-8185 3360);
DISPLAY 0.808511 (-8185 3360);
WIRE 16 -1 (-2825 3450)(-4175 3450);
FORCEPROP 2 LAST SIG_NAME PU_FPGA_NSTATUS
J 2
(-2825 3460);
DISPLAY 0.808511 (-2825 3460);
WIRE 16 -1 (-4175 3550)(-1125 3550);
FORCEPROP 2 LAST SIG_NAME FM_THERMTRIP_DLY_LVC1_R_N
J 0
(-3985 3560);
DISPLAY 0.808511 (-3985 3560);
WIRE 16 -1 (-2650 3600)(-4175 3600);
FORCEPROP 2 LAST SIG_NAME SGPIO_PLD_DI_0
J 0
(-3985 3610);
DISPLAY 0.808511 (-3985 3610);
WIRE 16 -1 (-2650 3700)(-4175 3700);
FORCEPROP 2 LAST SIG_NAME SGPIO_PLD_LD_0
J 0
(-3985 3710);
DISPLAY 0.808511 (-3985 3710);
WIRE 16 -1 (-2650 3750)(-4175 3750);
FORCEPROP 2 LAST SIG_NAME SGPIO_PLD_DO_0
J 0
(-3985 3760);
DISPLAY 0.808511 (-3985 3760);
WIRE 16 -1 (-4175 3850)(-2650 3850);
FORCEPROP 2 LAST SIG_NAME SGPIO_CLK_PLD_0
J 0
(-3985 3860);
DISPLAY 0.808511 (-3985 3860);
WIRE 16 -1 (-4175 3900)(-1125 3900);
FORCEPROP 2 LAST SIG_NAME IRQ_OC_DETECT_EN_N
J 2
(-1100 3910);
DISPLAY 0.808511 (-1100 3910);
WIRE 16 -1 (-1125 4000)(-4175 4000);
FORCEPROP 2 LAST SIG_NAME FM_ADR_COMPLETE
J 2
(-1100 4010);
DISPLAY 0.808511 (-1100 4010);
WIRE 16 -1 (-4175 4450)(-2650 4450);
FORCEPROP 2 LAST SIG_NAME PU_PT20D
J 0
(-3985 4460);
DISPLAY 0.851064 (-3985 4460);
WIRE 16 -1 (-4175 4500)(-2650 4500);
FORCEPROP 2 LAST SIG_NAME JTAG_SCM_PLD_R_JTAGEN
J 0
(-3985 4510);
DISPLAY 0.851064 (-3985 4510);
WIRE 16 -1 (-1125 4600)(-2450 4600);
FORCEPROP 2 LAST SIG_NAME FM_CPU_MSMI_CATERR_LVT3_N
J 0
(-2060 4610);
DISPLAY 0.808511 (-2060 4610);
WIRE 16 -1 (-1125 4500)(-2450 4500);
FORCEPROP 2 LAST SIG_NAME JTAG_SCM_PLD_JTAGEN
J 0
(-1935 4510);
DISPLAY 0.808511 (-1935 4510);
WIRE 16 -1 (-2450 4350)(-1125 4350);
FORCEPROP 2 LAST SIG_NAME RST_EXTRST_N
J 2
(-1100 4360);
DISPLAY 0.808511 (-1100 4360);
WIRE 16 -1 (-4175 5100)(-2825 5100);
FORCEPROP 2 LAST SIG_NAME SMB_BMC_MM16_R3_SCL
J 0
(-3985 5110);
DISPLAY 0.851064 (-3985 5110);
WIRE 16 -1 (-4175 5250)(-2825 5250);
FORCEPROP 2 LAST SIG_NAME RST_SRST_PLD_BMC_R2_N
J 0
(-3985 5260);
DISPLAY 0.851064 (-3985 5260);
WIRE 16 -1 (-4175 5050)(-2825 5050);
FORCEPROP 2 LAST SIG_NAME SMB_BMC_MM16_R3_SDA
J 0
(-3985 5060);
DISPLAY 0.851064 (-3985 5060);
WIRE 16 -1 (-2625 5250)(-1125 5250);
FORCEPROP 2 LAST SIG_NAME RST_SRST_PLD_BMC_R_N
J 2
(-1160 5260);
DISPLAY 0.808511 (-1160 5260);
WIRE 16 -1 (-1125 3600)(-2450 3600);
FORCEPROP 2 LAST SIG_NAME SGPIO_DI_0
J 2
(-1100 3610);
DISPLAY 0.808511 (-1100 3610);
WIRE 16 -1 (-1125 3700)(-2450 3700);
FORCEPROP 2 LAST SIG_NAME SGPIO_LD_0
J 2
(-1100 3710);
DISPLAY 0.808511 (-1100 3710);
WIRE 16 -1 (-1125 3750)(-2450 3750);
FORCEPROP 2 LAST SIG_NAME SGPIO_DO_0
J 2
(-1100 3760);
DISPLAY 0.808511 (-1100 3760);
WIRE 16 -1 (-2450 3850)(-1125 3850);
FORCEPROP 2 LAST SIG_NAME SGPIO_CLK_0
J 2
(-1100 3860);
DISPLAY 0.808511 (-1100 3860);
WIRE 16 -1 (-2825 3400)(-4175 3400);
FORCEPROP 2 LAST SIG_NAME PU_FPGA_CONFIG_DONE
J 2
(-2825 3410);
DISPLAY 0.808511 (-2825 3410);
WIRE 16 -1 (-8225 3850)(-5625 3850);
FORCEPROP 2 LAST SIG_NAME FM_PCIE_M2_SSD0_PRSNT_N
J 0
(-8225 3860);
DISPLAY 0.808511 (-8225 3860);
WIRE 16 -1 (-8225 3800)(-5625 3800);
FORCEPROP 2 LAST SIG_NAME FM_BIOS_POST_CMPLT_BMC_N
J 0
(-8210 3810);
DISPLAY 0.808511 (-8210 3810);
WIRE 16 -1 (-5625 5150)(-6900 5150);
FORCEPROP 2 LAST SIG_NAME FM_TPM_PRSNT_1_R_N
J 0
(-6610 5160);
DISPLAY 0.808511 (-6610 5160);
WIRE 16 -1 (-6900 5200)(-5625 5200);
FORCEPROP 2 LAST SIG_NAME FM_TPM_PRSNT_0_R_N
J 0
(-6610 5210);
DISPLAY 0.808511 (-6610 5210);
WIRE 16 -1 (-8225 5200)(-7100 5200);
FORCEPROP 2 LAST SIG_NAME FM_TPM_PRSNT_0_N
J 0
(-8185 5210);
DISPLAY 0.808511 (-8185 5210);
WIRE 16 -1 (-7100 5150)(-8225 5150);
FORCEPROP 2 LAST SIG_NAME FM_TPM_PRSNT_1_N
J 0
(-8185 5160);
DISPLAY 0.808511 (-8185 5160);
WIRE 16 -1 (-5625 4500)(-8225 4500);
FORCEPROP 2 LAST SIG_NAME FM_BMC_DBP_PRESENT_N
J 0
(-8210 4510);
DISPLAY 0.808511 (-8210 4510);
WIRE 16 -1 (-8225 4650)(-7100 4650);
FORCEPROP 2 LAST SIG_NAME BSM_PRSNT_R_N
J 0
(-8185 4660);
DISPLAY 0.808511 (-8185 4660);
WIRE 16 -1 (-8225 4750)(-7100 4750);
FORCEPROP 2 LAST SIG_NAME FM_JTAG_BMC_MUX_SEL
J 0
(-8185 4760);
DISPLAY 0.851064 (-8185 4760);
WIRE 16 -1 (-7100 4900)(-8225 4900);
FORCEPROP 2 LAST SIG_NAME PWRGD_PSU_AC_PWROK
J 0
(-8185 4910);
DISPLAY 0.808511 (-8185 4910);
WIRE 16 -1 (-8225 4950)(-7100 4950);
FORCEPROP 2 LAST SIG_NAME RST_PLTRST_N
J 0
(-8175 4960);
DISPLAY 0.808511 (-8175 4960);
WIRE 16 -1 (-8225 4450)(-5625 4450);
FORCEPROP 2 LAST SIG_NAME PWRGD_PCH_PWROK
J 0
(-8210 4460);
DISPLAY 0.808511 (-8210 4460);
WIRE 16 -1 (-8125 5950)(-8750 5950);
FORCEPROP 2 LAST SIG_NAME RST_RSMRST_N
J 0
(-8635 5960);
DISPLAY 0.808511 (-8635 5960);
WIRE 16 -1 (-8750 6050)(-8750 5950);
WIRE 16 -1 (-5625 4300)(-6675 4300);
FORCEPROP 2 LAST SIG_NAME JTAG_SCM_PLD_TDO
J 0
(-6625 4310);
DISPLAY 0.808511 (-6625 4310);
WIRE 16 -1 (-5625 4250)(-6675 4250);
FORCEPROP 2 LAST SIG_NAME JTAG_SCM_PLD_TDI
J 0
(-6625 4260);
DISPLAY 0.808511 (-6625 4260);
WIRE 16 -1 (-3550 700)(-4375 700);
FORCEPROP 2 LAST SIG_NAME PU_25M_FPGA_CLK_EN
J 0
(-4335 710);
DISPLAY 0.808511 (-4335 710);
WIRE 16 -1 (-4375 850)(-4375 700);
WIRE 16 -1 (-8225 3500)(-7150 3500);
FORCEPROP 2 LAST SIG_NAME IRQ_BMC_PCH_NMI_N
J 0
(-8210 3510);
DISPLAY 0.808511 (-8210 3510);
WIRE 16 -1 (-1700 850)(-850 850);
FORCEPROP 2 LAST SIG_NAME CLK_25M_OSC_FPGA
J 0
(-1485 860);
DISPLAY 0.808511 (-1485 860);
WIRE 16 -1 (-7050 650)(-8275 650);
FORCEPROP 2 LAST SIG_NAME PU_FPGA_NSTATUS
J 0
(-8125 660);
DISPLAY 0.808511 (-8125 660);
WIRE 16 -1 (-7050 700)(-8275 700);
FORCEPROP 2 LAST SIG_NAME PU_FPGA_NCONFIG
J 0
(-8125 710);
DISPLAY 0.808511 (-8125 710);
WIRE 16 -1 (-7050 750)(-8275 750);
FORCEPROP 2 LAST SIG_NAME PU_FPGA_CONFIG_DONE
J 0
(-8125 760);
DISPLAY 0.808511 (-8125 760);
WIRE 16 -1 (-8225 4000)(-7225 4000);
FORCEPROP 2 LAST SIG_NAME BMC_CPLD_GPIO_2
J 0
(-8235 4010);
DISPLAY 0.851064 (-8235 4010);
DOT 1 (-5825 3050);
DOT 1 (-6725 1850);
DOT 1 (-6725 1375);
DOT 1 (-6400 750);
DOT 1 (-6400 700);
DOT 1 (-7375 1850);
DOT 1 (-3975 1325);
DOT 1 (-3975 3100);
FORCENOTE
FOR CPLD
(-3450 1425) 0;
DISPLAY LEFT (-3450 1425);
DISPLAY 2.000000 (-3450 1425);
PAINT WHITE (-3450 1425);
QUIT
